FILE_TYPE = MACRO_DRAWING;
SET COLOR_WIRE YELLOW;
SET COLOR_PROP ORANGE;
SET COLOR_DOT WHITE;
SET COLOR_ARC YELLOW;
SET COLOR_BODY GREEN;
SET COLOR_NOTE PURPLE;
SET PROP_DISPLAY VALUE;
SET PAGE_NUMBER P232;
FORCEADD OFFPAGE..1
(-8100 3500);
FORCEPROP 2 LAST $XR2 112 
J 0
(-8592 3500);
DISPLAY 0.638298 (-8592 3500);
PAINT MONO (-8592 3500);
FORCEPROP 2 LAST $XR1 234 
J 0
(-8472 3500);
DISPLAY 0.638298 (-8472 3500);
PAINT MONO (-8472 3500);
FORCEPROP 2 LAST $XR0 111 
J 0
(-8352 3500);
DISPLAY 0.638298 (-8352 3500);
PAINT MONO (-8352 3500);
FORCEPROP 2 LAST CDS_LIB standard
J 0
(-8100 3500);
DISPLAY INVISIBLE (-8100 3500);
FORCEPROP 1 LAST OFFPAGE TRUE
J 0
(-7775 3375);
DISPLAY 1.170213 (-7775 3375);
PAINT GREEN (-7775 3375);
DISPLAY INVISIBLE (-7775 3375);
FORCEPROP 1 LAST COMMENT_BODY TRUE
J 0
(-7975 3400);
DISPLAY 1.170213 (-7975 3400);
PAINT GREEN (-7975 3400);
DISPLAY INVISIBLE (-7975 3400);
FORCEPROP 2 LAST PATH I1
J 0
(-8375 3550);
DISPLAY 0.680851 (-8375 3550);
DISPLAY INVISIBLE (-8375 3550);
FORCEADD UNIVERSAL_GND..1
(-7250 3700);
FORCEPROP 3 LASTPIN (-7250 3750) SIG_NAME GND\g
J 0
(-7240 3760);
DISPLAY 0.659574 (-7240 3760);
PAINT MONO (-7240 3760);
DISPLAY INVISIBLE (-7240 3760);
FORCEPROP 2 LAST CDS_LIB pure_quanta_power
J 0
(-7250 3700);
DISPLAY INVISIBLE (-7250 3700);
FORCEPROP 1 LAST HDL_POWER GND
J 1
(-7225 3625);
DISPLAY 0.872340 (-7225 3625);
PAINT GREEN (-7225 3625);
DISPLAY INVISIBLE (-7225 3625);
FORCEPROP 1 LAST PATH I11
J 0
(-7175 3700);
DISPLAY 0.872340 (-7175 3700);
PAINT AQUA (-7175 3700);
DISPLAY INVISIBLE (-7175 3700);
FORCEADD UNIVERSAL_GND..1
(-7125 3800);
FORCEPROP 3 LASTPIN (-7125 3850) SIG_NAME GND\g
J 0
(-7115 3860);
DISPLAY 0.659574 (-7115 3860);
PAINT MONO (-7115 3860);
DISPLAY INVISIBLE (-7115 3860);
FORCEPROP 2 LAST CDS_LIB pure_quanta_power
J 0
(-7125 3800);
DISPLAY INVISIBLE (-7125 3800);
FORCEPROP 1 LAST HDL_POWER GND
J 1
(-7100 3725);
DISPLAY 0.872340 (-7100 3725);
PAINT GREEN (-7100 3725);
DISPLAY INVISIBLE (-7100 3725);
FORCEPROP 1 LAST PATH I12
J 0
(-7050 3800);
DISPLAY 0.872340 (-7050 3800);
PAINT AQUA (-7050 3800);
DISPLAY INVISIBLE (-7050 3800);
FORCEADD Q_XTAL_4P_13BI_24GND..1
(-6800 4025);
FORCEPROP 1 LAST LOCATION Y8003
J 0
(-6925 4375);
DISPLAY 0.723404 (-6925 4375);
PAINT GREEN (-6925 4375);
FORCEPROP 0 LAST $SEC 1
J 0
(-6925 4525);
DISPLAY 0.680851 (-6925 4525);
PAINT MONO (-6925 4525);
DISPLAY INVISIBLE (-6925 4525);
FORCEPROP 0 LAST CDS_SEC 1
J 0
(-6925 4525);
DISPLAY 1.021277 (-6925 4525);
DISPLAY INVISIBLE (-6925 4525);
FORCEPROP 0 LASTPIN (-7075 3900) $PN 2
J 2
(-7085 3910);
DISPLAY 0.680851 (-7085 3910);
PAINT MONO (-7085 3910);
FORCEPROP 0 LASTPIN (-6525 3900) $PN 4
J 0
(-6515 3910);
DISPLAY 0.680851 (-6515 3910);
PAINT MONO (-6515 3910);
FORCEPROP 0 LASTPIN (-7075 4100) $PN 1
J 2
(-7085 4110);
DISPLAY 0.680851 (-7085 4110);
PAINT MONO (-7085 4110);
FORCEPROP 0 LASTPIN (-6525 4100) $PN 3
J 0
(-6515 4110);
DISPLAY 0.680851 (-6515 4110);
PAINT MONO (-6515 4110);
FORCEPROP 2 LAST VALUE 25MHZ
J 0
(-6925 4425);
DISPLAY 1.021277 (-6925 4425);
FORCEPROP 2 LAST PART_TYPE SMLF
J 0
(-6925 4475);
DISPLAY 1.021277 (-6925 4475);
FORCEPROP 1 LAST MATERIAL MISC
J 0
(-6933 4204);
DISPLAY 0.723404 (-6933 4204);
PAINT GREEN (-6933 4204);
FORCEPROP 2 LAST CDS_LIB pure_quanta
J 0
(-6800 4025);
DISPLAY INVISIBLE (-6800 4025);
FORCEPROP 1 LAST CDS_LMAN_SYM_OUTLINE -125,175,125,-175
J 0
(-6800 4025);
DISPLAY 0.468085 (-6800 4025);
PAINT GREEN (-6800 4025);
DISPLAY INVISIBLE (-6800 4025);
FORCEPROP 1 LAST PIN_NAMES_ROTATE True
J 0
(-6800 4025);
DISPLAY 0.489362 (-6800 4025);
PAINT GREEN (-6800 4025);
DISPLAY INVISIBLE (-6800 4025);
FORCEPROP 1 LAST PATH I14
J 0
(-6675 3850);
DISPLAY 0.723404 (-6675 3850);
PAINT GREEN (-6675 3850);
DISPLAY INVISIBLE (-6675 3850);
FORCEPROP 1 LAST PART_NUMBER BG6250000L4
J 0
(-6933 4300);
DISPLAY 0.723404 (-6933 4300);
PAINT GREEN (-6933 4300);
DISPLAY INVISIBLE (-6933 4300);
FORCEADD UNIVERSAL_POWER..1
(-6325 2075);
FORCEPROP 3 LASTPIN (-6325 2025) SIG_NAME P3V3_AUX\g
J 0
(-6315 2035);
DISPLAY 0.659574 (-6315 2035);
PAINT MONO (-6315 2035);
DISPLAY INVISIBLE (-6315 2035);
FORCEPROP 1 LAST HDL_POWER P3V3_AUX
J 1
(-6325 2125);
DISPLAY 0.872340 (-6325 2125);
PAINT GREEN (-6325 2125);
FORCEPROP 2 LAST CDS_LIB pure_quanta_power
J 0
(-6325 2075);
DISPLAY INVISIBLE (-6325 2075);
FORCEPROP 1 LAST PATH I15
J 0
(-6275 2100);
DISPLAY 0.872340 (-6275 2100);
PAINT AQUA (-6275 2100);
DISPLAY INVISIBLE (-6275 2100);
FORCEADD Q_RES..1
(-6200 3500);
FORCEPROP 1 LAST LOCATION R4076
J 0
(-6400 3500);
DISPLAY 0.638298 (-6400 3500);
FORCEPROP 0 LAST $SEC 1
J 0
(-6025 3550);
DISPLAY 0.680851 (-6025 3550);
PAINT MONO (-6025 3550);
DISPLAY INVISIBLE (-6025 3550);
FORCEPROP 0 LAST CDS_SEC 1
J 0
(-6025 3550);
DISPLAY 1.021277 (-6025 3550);
DISPLAY INVISIBLE (-6025 3550);
FORCEPROP 1 LASTPIN (-6300 3500) $PN 1
J 0
(-6288 3512);
DISPLAY 0.787234 (-6288 3512);
PAINT MONO (-6288 3512);
FORCEPROP 1 LASTPIN (-6100 3500) $PN 2
J 0
(-6138 3512);
DISPLAY 0.787234 (-6138 3512);
PAINT MONO (-6138 3512);
FORCEPROP 1 LAST PACK_TYPE 0402LF
J 0
(-6325 3375);
DISPLAY 0.638298 (-6325 3375);
FORCEPROP 1 LAST WATTAGE 1/16W
J 2
(-6125 3325);
DISPLAY 0.638298 (-6125 3325);
FORCEPROP 1 LAST TOLERANCE 5%
J 0
(-6125 3375);
DISPLAY 0.638298 (-6125 3375);
FORCEPROP 1 LAST VALUE 0
J 2
(-6050 3500);
DISPLAY 0.787234 (-6050 3500);
FORCEPROP 1 LAST MATERIAL CHIP
J 0
(-6025 3500);
DISPLAY 0.638298 (-6025 3500);
FORCEPROP 2 LAST CDS_LIB pure_quanta
J 0
(-6200 3500);
DISPLAY INVISIBLE (-6200 3500);
FORCEPROP 1 LAST PATH I16
J 0
(-6250 3650);
DISPLAY 0.978723 (-6250 3650);
PAINT WHITE (-6250 3650);
DISPLAY INVISIBLE (-6250 3650);
FORCEPROP 1 LAST PART_NUMBER CS00002JB13
J 0
(-6350 3425);
DISPLAY 0.638298 (-6350 3425);
DISPLAY INVISIBLE (-6350 3425);
FORCEADD OFFPAGE..1
(-5975 3150);
FORCEPROP 2 LAST $XR0 234 
J 0
(-6227 3150);
DISPLAY 0.638298 (-6227 3150);
PAINT MONO (-6227 3150);
FORCEPROP 2 LAST CDS_LIB standard
J 0
(-5975 3150);
DISPLAY INVISIBLE (-5975 3150);
FORCEPROP 1 LAST OFFPAGE TRUE
J 0
(-5650 3025);
DISPLAY 1.170213 (-5650 3025);
PAINT GREEN (-5650 3025);
DISPLAY INVISIBLE (-5650 3025);
FORCEPROP 1 LAST COMMENT_BODY TRUE
J 0
(-5850 3050);
DISPLAY 1.170213 (-5850 3050);
PAINT GREEN (-5850 3050);
DISPLAY INVISIBLE (-5850 3050);
FORCEPROP 2 LAST PATH I17
J 0
(-6250 3200);
DISPLAY 0.680851 (-6250 3200);
DISPLAY INVISIBLE (-6250 3200);
FORCEADD OFFPAGE..1
(-5975 3250);
FORCEPROP 2 LAST $XR0 234 
J 0
(-6227 3250);
DISPLAY 0.638298 (-6227 3250);
PAINT MONO (-6227 3250);
FORCEPROP 2 LAST CDS_LIB standard
J 0
(-5975 3250);
DISPLAY INVISIBLE (-5975 3250);
FORCEPROP 1 LAST OFFPAGE TRUE
J 0
(-5650 3125);
DISPLAY 1.170213 (-5650 3125);
PAINT GREEN (-5650 3125);
DISPLAY INVISIBLE (-5650 3125);
FORCEPROP 1 LAST COMMENT_BODY TRUE
J 0
(-5850 3150);
DISPLAY 1.170213 (-5850 3150);
PAINT GREEN (-5850 3150);
DISPLAY INVISIBLE (-5850 3150);
FORCEPROP 2 LAST PATH I18
J 0
(-6250 3300);
DISPLAY 0.680851 (-6250 3300);
DISPLAY INVISIBLE (-6250 3300);
FORCEADD UNIVERSAL_GND..1
(-6375 3675);
FORCEPROP 3 LASTPIN (-6375 3725) SIG_NAME GND\g
J 0
(-6365 3735);
DISPLAY 0.659574 (-6365 3735);
PAINT MONO (-6365 3735);
DISPLAY INVISIBLE (-6365 3735);
FORCEPROP 2 LAST CDS_LIB pure_quanta_power
J 0
(-6375 3675);
DISPLAY INVISIBLE (-6375 3675);
FORCEPROP 1 LAST HDL_POWER GND
J 1
(-6350 3600);
DISPLAY 0.872340 (-6350 3600);
PAINT GREEN (-6350 3600);
DISPLAY INVISIBLE (-6350 3600);
FORCEPROP 1 LAST PATH I19
J 0
(-6300 3675);
DISPLAY 0.872340 (-6300 3675);
PAINT AQUA (-6300 3675);
DISPLAY INVISIBLE (-6300 3675);
FORCEADD OFFPAGE..1
(-8100 3550);
FORCEPROP 2 LAST $XR0 80 
J 0
(-8321 3550);
DISPLAY 0.638298 (-8321 3550);
PAINT MONO (-8321 3550);
FORCEPROP 2 LAST CDS_LIB standard
J 0
(-8100 3550);
DISPLAY INVISIBLE (-8100 3550);
FORCEPROP 1 LAST OFFPAGE TRUE
J 0
(-7775 3425);
DISPLAY 1.170213 (-7775 3425);
PAINT GREEN (-7775 3425);
DISPLAY INVISIBLE (-7775 3425);
FORCEPROP 1 LAST COMMENT_BODY TRUE
J 0
(-7975 3450);
DISPLAY 1.170213 (-7975 3450);
PAINT GREEN (-7975 3450);
DISPLAY INVISIBLE (-7975 3450);
FORCEPROP 2 LAST PATH I2
J 0
(-8375 3600);
DISPLAY 0.680851 (-8375 3600);
DISPLAY INVISIBLE (-8375 3600);
FORCEADD UNIVERSAL_GND..1
(-6475 3800);
FORCEPROP 3 LASTPIN (-6475 3850) SIG_NAME GND\g
J 0
(-6465 3860);
DISPLAY 0.659574 (-6465 3860);
PAINT MONO (-6465 3860);
DISPLAY INVISIBLE (-6465 3860);
FORCEPROP 2 LAST CDS_LIB pure_quanta_power
J 0
(-6475 3800);
DISPLAY INVISIBLE (-6475 3800);
FORCEPROP 1 LAST HDL_POWER GND
J 1
(-6450 3725);
DISPLAY 0.872340 (-6450 3725);
PAINT GREEN (-6450 3725);
DISPLAY INVISIBLE (-6450 3725);
FORCEPROP 1 LAST PATH I20
J 0
(-6400 3800);
DISPLAY 0.872340 (-6400 3800);
PAINT AQUA (-6400 3800);
DISPLAY INVISIBLE (-6400 3800);
FORCEADD Q_RES..1
(-6200 3550);
FORCEPROP 1 LAST LOCATION R4075
J 0
(-6400 3550);
DISPLAY 0.638298 (-6400 3550);
FORCEPROP 0 LAST $SEC 1
J 0
(-6025 3600);
DISPLAY 0.680851 (-6025 3600);
PAINT MONO (-6025 3600);
DISPLAY INVISIBLE (-6025 3600);
FORCEPROP 0 LAST CDS_SEC 1
J 0
(-6025 3600);
DISPLAY 1.021277 (-6025 3600);
DISPLAY INVISIBLE (-6025 3600);
FORCEPROP 1 LASTPIN (-6300 3550) $PN 1
J 0
(-6288 3562);
DISPLAY 0.787234 (-6288 3562);
PAINT MONO (-6288 3562);
FORCEPROP 1 LASTPIN (-6100 3550) $PN 2
J 0
(-6138 3562);
DISPLAY 0.787234 (-6138 3562);
PAINT MONO (-6138 3562);
FORCEPROP 1 LAST VALUE 0
J 2
(-6050 3550);
DISPLAY 0.787234 (-6050 3550);
FORCEPROP 1 LAST MATERIAL CHIP
J 0
(-6025 3550);
DISPLAY 0.638298 (-6025 3550);
FORCEPROP 1 LAST WATTAGE 1/16W
J 2
(-6125 3375);
DISPLAY 0.638298 (-6125 3375);
DISPLAY INVISIBLE (-6125 3375);
FORCEPROP 1 LAST TOLERANCE 5%
J 0
(-6125 3425);
DISPLAY 0.638298 (-6125 3425);
DISPLAY INVISIBLE (-6125 3425);
FORCEPROP 1 LAST PACK_TYPE 0402LF
J 0
(-6325 3425);
DISPLAY 0.638298 (-6325 3425);
DISPLAY INVISIBLE (-6325 3425);
FORCEPROP 2 LAST CDS_LIB pure_quanta
J 0
(-6200 3550);
DISPLAY INVISIBLE (-6200 3550);
FORCEPROP 1 LAST PATH I22
J 0
(-6250 3700);
DISPLAY 0.978723 (-6250 3700);
PAINT WHITE (-6250 3700);
DISPLAY INVISIBLE (-6250 3700);
FORCEPROP 1 LAST PART_NUMBER CS00002JB13
J 0
(-6325 3475);
DISPLAY 0.638298 (-6325 3475);
DISPLAY INVISIBLE (-6325 3475);
FORCEADD OFFPAGE..3
R 2
(-5775 3650);
FORCEPROP 2 LAST $XR0 151 
J 0
(-6055 3650);
DISPLAY 0.638298 (-6055 3650);
PAINT MONO (-6055 3650);
FORCEPROP 2 LAST CDS_LIB standard
J 2
(-5775 3650);
PAINT MONO (-5775 3650);
DISPLAY INVISIBLE (-5775 3650);
FORCEPROP 1 LAST OFFPAGE TRUE
J 2
(-6100 3525);
DISPLAY 0.872340 (-6100 3525);
PAINT GREEN (-6100 3525);
DISPLAY INVISIBLE (-6100 3525);
FORCEPROP 1 LAST COMMENT_BODY TRUE
J 2
(-5725 3550);
DISPLAY 0.872340 (-5725 3550);
PAINT GREEN (-5725 3550);
DISPLAY INVISIBLE (-5725 3550);
FORCEPROP 2 LAST PATH I23
J 0
(-6050 3700);
DISPLAY 0.680851 (-6050 3700);
DISPLAY INVISIBLE (-6050 3700);
FORCEADD OFFPAGE..2
R 2
(-5775 3700);
FORCEPROP 2 LAST $XR0 151 
J 0
(-6030 3700);
DISPLAY 0.638298 (-6030 3700);
PAINT MONO (-6030 3700);
FORCEPROP 2 LAST CDS_LIB standard
J 2
(-5775 3700);
PAINT MONO (-5775 3700);
DISPLAY INVISIBLE (-5775 3700);
FORCEPROP 1 LAST OFFPAGE TRUE
J 2
(-6100 3575);
DISPLAY 0.872340 (-6100 3575);
PAINT GREEN (-6100 3575);
DISPLAY INVISIBLE (-6100 3575);
FORCEPROP 1 LAST COMMENT_BODY TRUE
J 2
(-5730 3605);
DISPLAY 0.872340 (-5730 3605);
PAINT GREEN (-5730 3605);
DISPLAY INVISIBLE (-5730 3605);
FORCEPROP 2 LAST PATH I24
J 0
(-6025 3750);
DISPLAY 0.680851 (-6025 3750);
DISPLAY INVISIBLE (-6025 3750);
FORCEADD UNIVERSAL_GND..1
(-5450 1175);
FORCEPROP 3 LASTPIN (-5450 1225) SIG_NAME GND\g
J 0
(-5440 1235);
DISPLAY 0.659574 (-5440 1235);
PAINT MONO (-5440 1235);
DISPLAY INVISIBLE (-5440 1235);
FORCEPROP 2 LAST CDS_LIB pure_quanta_power
J 0
(-5450 1175);
DISPLAY INVISIBLE (-5450 1175);
FORCEPROP 1 LAST HDL_POWER GND
J 1
(-5425 1100);
DISPLAY 0.872340 (-5425 1100);
PAINT GREEN (-5425 1100);
DISPLAY INVISIBLE (-5425 1100);
FORCEPROP 1 LAST PATH I25
J 0
(-5375 1175);
DISPLAY 0.872340 (-5375 1175);
PAINT AQUA (-5375 1175);
DISPLAY INVISIBLE (-5375 1175);
FORCEADD 74LVC1G32GW..1
(-5125 1450);
FORCEPROP 1 LAST LOCATION U248
J 0
(-5275 1705);
DISPLAY 0.723404 (-5275 1705);
PAINT GREEN (-5275 1705);
FORCEPROP 0 LAST $SEC 1
J 0
(-5275 1850);
DISPLAY 0.680851 (-5275 1850);
PAINT MONO (-5275 1850);
DISPLAY INVISIBLE (-5275 1850);
FORCEPROP 0 LAST CDS_SEC 1
J 0
(-5275 1850);
DISPLAY 1.021277 (-5275 1850);
DISPLAY INVISIBLE (-5275 1850);
FORCEPROP 0 LASTPIN (-5325 1350) $PN 3
J 2
(-5335 1360);
DISPLAY 0.680851 (-5335 1360);
PAINT MONO (-5335 1360);
FORCEPROP 0 LASTPIN (-5425 1500) $PN 1
J 2
(-5435 1510);
DISPLAY 0.680851 (-5435 1510);
PAINT MONO (-5435 1510);
FORCEPROP 0 LASTPIN (-5425 1400) $PN 2
J 2
(-5435 1410);
DISPLAY 0.680851 (-5435 1410);
PAINT MONO (-5435 1410);
FORCEPROP 0 LASTPIN (-4825 1450) $PN 4
J 0
(-4815 1460);
DISPLAY 0.680851 (-4815 1460);
PAINT MONO (-4815 1460);
FORCEPROP 0 LASTPIN (-5325 1550) $PN 5
J 2
(-5335 1560);
DISPLAY 0.680851 (-5335 1560);
PAINT MONO (-5335 1560);
FORCEPROP 2 LAST PACK_TYPE SMLF
J 0
(-5275 1750);
DISPLAY 1.021277 (-5275 1750);
FORCEPROP 1 LAST MATERIAL IC
J 0
(-5275 1585);
DISPLAY 0.723404 (-5275 1585);
PAINT GREEN (-5275 1585);
FORCEPROP 2 LAST VALUE 74LVC1G32GW
J 0
(-5275 1800);
DISPLAY 1.021277 (-5275 1800);
FORCEPROP 2 LAST CDS_LIB pure_quanta
J 0
(-5125 1450);
DISPLAY INVISIBLE (-5125 1450);
FORCEPROP 1 LAST NEEDS_NO_SIZE TRUE
J 0
(-5125 1450);
DISPLAY 0.468085 (-5125 1450);
PAINT GREEN (-5125 1450);
DISPLAY INVISIBLE (-5125 1450);
FORCEPROP 1 LAST PATH I26
J 0
(-5100 1580);
DISPLAY 0.723404 (-5100 1580);
PAINT GREEN (-5100 1580);
DISPLAY INVISIBLE (-5100 1580);
FORCEPROP 1 LAST PART_NUMBER ALVC1G32007
J 0
(-5275 1635);
DISPLAY 0.723404 (-5275 1635);
PAINT GREEN (-5275 1635);
DISPLAY INVISIBLE (-5275 1635);
FORCEADD UNIVERSAL_GND..1
(-5275 1875);
FORCEPROP 3 LASTPIN (-5275 1925) SIG_NAME GND\g
J 0
(-5265 1935);
DISPLAY 0.659574 (-5265 1935);
PAINT MONO (-5265 1935);
DISPLAY INVISIBLE (-5265 1935);
FORCEPROP 2 LAST CDS_LIB pure_quanta_power
J 0
(-5275 1875);
PAINT MONO (-5275 1875);
DISPLAY INVISIBLE (-5275 1875);
FORCEPROP 1 LAST HDL_POWER GND
J 1
(-5250 1800);
DISPLAY 0.872340 (-5250 1800);
PAINT GREEN (-5250 1800);
DISPLAY INVISIBLE (-5250 1800);
FORCEPROP 1 LAST PATH I27
J 0
(-5200 1875);
DISPLAY 0.872340 (-5200 1875);
PAINT AQUA (-5200 1875);
DISPLAY INVISIBLE (-5200 1875);
FORCEADD Q_CAP..1
(-5275 2125);
FORCEPROP 1 LAST LOCATION C1882
J 0
(-5225 2225);
DISPLAY 0.638298 (-5225 2225);
FORCEPROP 2 LAST $SEC 1
J 2
(-5225 2325);
DISPLAY 0.680851 (-5225 2325);
PAINT MONO (-5225 2325);
DISPLAY INVISIBLE (-5225 2325);
FORCEPROP 2 LAST CDS_SEC 1
J 2
(-5225 2325);
DISPLAY 1.021277 (-5225 2325);
DISPLAY INVISIBLE (-5225 2325);
FORCEPROP 1 LASTPIN (-5275 2225) $PN 1
J 0
(-5265 2205);
DISPLAY 0.787234 (-5265 2205);
FORCEPROP 1 LASTPIN (-5275 2025) $PN 2
J 0
(-5265 2005);
DISPLAY 0.787234 (-5265 2005);
FORCEPROP 1 LAST VOLTAGE 25V
J 0
(-5225 2125);
DISPLAY 0.510638 (-5225 2125);
FORCEPROP 1 LAST VALUE 0.1UF
J 0
(-5225 2175);
DISPLAY 0.510638 (-5225 2175);
FORCEPROP 1 LAST MATERIAL X7R
J 0
(-5225 2025);
DISPLAY 0.510638 (-5225 2025);
FORCEPROP 1 LAST TOLERANCE 10%
J 0
(-5225 2075);
DISPLAY 0.510638 (-5225 2075);
FORCEPROP 1 LAST PACK_TYPE 0402
J 0
(-5225 1925);
DISPLAY 0.510638 (-5225 1925);
FORCEPROP 2 LAST CDS_LIB pure_quanta
J 0
(-5275 2125);
PAINT MONO (-5275 2125);
DISPLAY INVISIBLE (-5275 2125);
FORCEPROP 1 LAST PATH I28
J 0
(-5225 2275);
DISPLAY 0.978723 (-5225 2275);
PAINT WHITE (-5225 2275);
DISPLAY INVISIBLE (-5225 2275);
FORCEPROP 1 LAST PART_NUMBER CH4104K1B00
J 0
(-5225 1975);
DISPLAY 0.510638 (-5225 1975);
DISPLAY INVISIBLE (-5225 1975);
FORCEADD UNIVERSAL_POWER..1
(-5275 2550);
FORCEPROP 3 LASTPIN (-5275 2500) SIG_NAME P3V3_AUX\g
J 0
(-5265 2510);
DISPLAY 0.659574 (-5265 2510);
PAINT MONO (-5265 2510);
DISPLAY INVISIBLE (-5265 2510);
FORCEPROP 1 LAST HDL_POWER P3V3_AUX
J 1
(-5275 2600);
DISPLAY 0.872340 (-5275 2600);
PAINT GREEN (-5275 2600);
FORCEPROP 2 LAST CDS_LIB pure_quanta_power
J 0
(-5275 2550);
PAINT MONO (-5275 2550);
DISPLAY INVISIBLE (-5275 2550);
FORCEPROP 1 LAST PATH I29
J 0
(-5225 2575);
DISPLAY 0.872340 (-5225 2575);
PAINT AQUA (-5225 2575);
DISPLAY INVISIBLE (-5225 2575);
FORCEADD OFFPAGE..1
(-7675 1400);
FORCEPROP 2 LAST $XR0 80 
J 0
(-7926 1400);
DISPLAY 0.638298 (-7926 1400);
PAINT MONO (-7926 1400);
FORCEPROP 2 LAST CDS_LIB standard
J 0
(-7675 1400);
DISPLAY INVISIBLE (-7675 1400);
FORCEPROP 1 LAST OFFPAGE TRUE
J 0
(-7350 1275);
DISPLAY 0.872340 (-7350 1275);
PAINT GREEN (-7350 1275);
DISPLAY INVISIBLE (-7350 1275);
FORCEPROP 1 LAST COMMENT_BODY TRUE
J 0
(-7550 1300);
DISPLAY 0.872340 (-7550 1300);
PAINT GREEN (-7550 1300);
DISPLAY INVISIBLE (-7550 1300);
FORCEPROP 2 LAST PATH I3
J 0
(-7950 1450);
DISPLAY 0.680851 (-7950 1450);
DISPLAY INVISIBLE (-7950 1450);
FORCEADD UNIVERSAL_POWER..1
(-7975 4200);
FORCEPROP 3 LASTPIN (-7975 4150) SIG_NAME P3V3_AUX\g
J 0
(-7965 4160);
DISPLAY 0.659574 (-7965 4160);
PAINT MONO (-7965 4160);
DISPLAY INVISIBLE (-7965 4160);
FORCEPROP 1 LAST HDL_POWER P3V3_AUX
J 1
(-7975 4250);
DISPLAY 0.872340 (-7975 4250);
PAINT GREEN (-7975 4250);
FORCEPROP 2 LAST CDS_LIB pure_quanta_power
J 0
(-7975 4200);
DISPLAY INVISIBLE (-7975 4200);
FORCEPROP 1 LAST PATH I30
J 0
(-7925 4225);
DISPLAY 0.872340 (-7925 4225);
PAINT AQUA (-7925 4225);
DISPLAY INVISIBLE (-7925 4225);
FORCEADD Q_RES..1
(-6375 4575);
FORCEPROP 1 LAST LOCATION R4501
J 0
(-6575 4575);
DISPLAY 0.638298 (-6575 4575);
FORCEPROP 0 LAST $SEC 1
J 0
(-6175 4750);
DISPLAY 0.680851 (-6175 4750);
PAINT MONO (-6175 4750);
DISPLAY INVISIBLE (-6175 4750);
FORCEPROP 0 LAST CDS_SEC 1
J 0
(-6175 4750);
DISPLAY 1.021277 (-6175 4750);
DISPLAY INVISIBLE (-6175 4750);
FORCEPROP 1 LASTPIN (-6475 4575) $PN 1
J 0
(-6463 4587);
DISPLAY 0.787234 (-6463 4587);
PAINT MONO (-6463 4587);
FORCEPROP 1 LASTPIN (-6275 4575) $PN 2
J 0
(-6313 4587);
DISPLAY 0.787234 (-6313 4587);
PAINT MONO (-6313 4587);
FORCEPROP 1 LAST PACK_TYPE 0402LF
J 0
(-6250 4625);
DISPLAY 0.638298 (-6250 4625);
FORCEPROP 1 LAST MATERIAL CHIP
J 0
(-6525 4725);
DISPLAY 0.510638 (-6525 4725);
FORCEPROP 1 LAST WATTAGE 1/16W
J 2
(-6175 4725);
DISPLAY 0.510638 (-6175 4725);
FORCEPROP 1 LAST VALUE 0
J 2
(-6375 4625);
DISPLAY 0.638298 (-6375 4625);
FORCEPROP 1 LAST TOLERANCE 5%
J 0
(-6350 4625);
DISPLAY 0.638298 (-6350 4625);
FORCEPROP 2 LAST CDS_LIB pure_quanta
J 0
(-6375 4575);
DISPLAY INVISIBLE (-6375 4575);
FORCEPROP 1 LAST PATH I31
J 0
(-6425 4725);
DISPLAY 0.978723 (-6425 4725);
PAINT WHITE (-6425 4725);
DISPLAY INVISIBLE (-6425 4725);
FORCEPROP 1 LAST PART_NUMBER CS00002JB13
J 0
(-6525 4675);
DISPLAY 0.510638 (-6525 4675);
DISPLAY INVISIBLE (-6525 4675);
FORCEADD UNIVERSAL_POWER..1
(-6400 5525);
FORCEPROP 3 LASTPIN (-6400 5475) SIG_NAME P3V3_AUX\g
J 0
(-6390 5485);
DISPLAY 0.659574 (-6390 5485);
PAINT MONO (-6390 5485);
DISPLAY INVISIBLE (-6390 5485);
FORCEPROP 1 LAST HDL_POWER P3V3_AUX
J 1
(-6400 5575);
DISPLAY 0.872340 (-6400 5575);
PAINT GREEN (-6400 5575);
FORCEPROP 2 LAST CDS_LIB pure_quanta_power
J 0
(-6400 5525);
DISPLAY INVISIBLE (-6400 5525);
FORCEPROP 1 LAST PATH I32
J 0
(-6350 5550);
DISPLAY 0.872340 (-6350 5550);
PAINT AQUA (-6350 5550);
DISPLAY INVISIBLE (-6350 5550);
FORCEADD Q_INDUCTOR..1
(-6050 5425);
FORCEPROP 1 LAST LOCATION L17
J 0
(-6175 5585);
DISPLAY 0.723404 (-6175 5585);
PAINT GREEN (-6175 5585);
FORCEPROP 0 LAST $SEC 1
J 0
(-6175 5725);
DISPLAY 0.680851 (-6175 5725);
PAINT MONO (-6175 5725);
DISPLAY INVISIBLE (-6175 5725);
FORCEPROP 0 LAST CDS_SEC 1
J 0
(-6175 5725);
DISPLAY 1.021277 (-6175 5725);
DISPLAY INVISIBLE (-6175 5725);
FORCEPROP 0 LASTPIN (-6150 5400) $PN 1
J 2
(-6160 5410);
DISPLAY 0.680851 (-6160 5410);
PAINT MONO (-6160 5410);
FORCEPROP 0 LASTPIN (-5950 5400) $PN 2
J 0
(-5940 5410);
DISPLAY 0.680851 (-5940 5410);
PAINT MONO (-5940 5410);
FORCEPROP 1 LAST MATERIAL IND
J 0
(-6175 5480);
DISPLAY 0.723404 (-6175 5480);
PAINT GREEN (-6175 5480);
FORCEPROP 2 LAST PACK_TYPE SMLF
J 0
(-6175 5675);
DISPLAY 0.638298 (-6175 5675);
FORCEPROP 2 LAST VALUE FCM2012KF-601T/0.5A
J 0
(-6175 5625);
DISPLAY 0.638298 (-6175 5625);
FORCEPROP 1 LAST NEEDS_NO_SIZE TRUE
J 0
(-6050 5425);
DISPLAY 0.468085 (-6050 5425);
PAINT GREEN (-6050 5425);
DISPLAY INVISIBLE (-6050 5425);
FORCEPROP 2 LAST CDS_LIB pure_quanta
J 0
(-6050 5425);
DISPLAY INVISIBLE (-6050 5425);
FORCEPROP 1 LAST PATH I33
J 0
(-5975 5480);
DISPLAY 0.723404 (-5975 5480);
PAINT GREEN (-5975 5480);
DISPLAY INVISIBLE (-5975 5480);
FORCEPROP 1 LAST PART_NUMBER CX601T05003
J 0
(-6175 5535);
DISPLAY 0.723404 (-6175 5535);
PAINT GREEN (-6175 5535);
DISPLAY INVISIBLE (-6175 5535);
FORCEADD UNIVERSAL_POWER..1
(-5750 4500);
FORCEPROP 3 LASTPIN (-5750 4450) SIG_NAME VFG3P3_CLK_GEN\g
J 0
(-5740 4460);
DISPLAY 0.659574 (-5740 4460);
PAINT MONO (-5740 4460);
DISPLAY INVISIBLE (-5740 4460);
FORCEPROP 1 LAST HDL_POWER VFG3P3_CLK_GEN
J 1
(-5750 4550);
DISPLAY 0.872340 (-5750 4550);
PAINT GREEN (-5750 4550);
FORCEPROP 2 LAST CDS_LIB pure_quanta_power
J 0
(-5750 4500);
DISPLAY INVISIBLE (-5750 4500);
FORCEPROP 1 LAST PATH I34
J 0
(-5700 4525);
DISPLAY 0.872340 (-5700 4525);
PAINT AQUA (-5700 4525);
DISPLAY INVISIBLE (-5700 4525);
FORCEADD UNIVERSAL_POWER..1
(-5400 4575);
FORCEPROP 3 LASTPIN (-5400 4525) SIG_NAME VFG_3P3A_CLK_GEN\g
J 0
(-5390 4535);
DISPLAY 0.659574 (-5390 4535);
PAINT MONO (-5390 4535);
DISPLAY INVISIBLE (-5390 4535);
FORCEPROP 1 LAST HDL_POWER VFG_3P3A_CLK_GEN
J 1
(-5400 4625);
DISPLAY 0.872340 (-5400 4625);
PAINT GREEN (-5400 4625);
FORCEPROP 2 LAST CDS_LIB pure_quanta_power
J 0
(-5400 4575);
DISPLAY INVISIBLE (-5400 4575);
FORCEPROP 1 LAST PATH I35
J 0
(-5350 4600);
DISPLAY 0.872340 (-5350 4600);
PAINT AQUA (-5350 4600);
DISPLAY INVISIBLE (-5350 4600);
FORCEADD Q_CAP..1
(-5700 5200);
FORCEPROP 1 LAST LOCATION C1883
J 0
(-5650 5300);
DISPLAY 0.787234 (-5650 5300);
FORCEPROP 0 LAST $SEC 1
J 0
(-5650 5350);
DISPLAY 0.680851 (-5650 5350);
PAINT MONO (-5650 5350);
DISPLAY INVISIBLE (-5650 5350);
FORCEPROP 0 LAST CDS_SEC 1
J 0
(-5650 5350);
DISPLAY 1.021277 (-5650 5350);
DISPLAY INVISIBLE (-5650 5350);
FORCEPROP 1 LASTPIN (-5700 5300) $PN 1
J 0
(-5690 5280);
DISPLAY 0.787234 (-5690 5280);
PAINT MONO (-5690 5280);
FORCEPROP 1 LASTPIN (-5700 5100) $PN 2
J 0
(-5690 5080);
DISPLAY 0.787234 (-5690 5080);
PAINT MONO (-5690 5080);
FORCEPROP 1 LAST VALUE 10UF
J 0
(-5650 5250);
DISPLAY 0.638298 (-5650 5250);
FORCEPROP 1 LAST MATERIAL X6S
J 0
(-5650 5100);
DISPLAY 0.638298 (-5650 5100);
FORCEPROP 1 LAST TOLERANCE 10%
J 0
(-5650 5150);
DISPLAY 0.638298 (-5650 5150);
FORCEPROP 1 LAST VOLTAGE 25V
J 0
(-5650 5200);
DISPLAY 0.638298 (-5650 5200);
FORCEPROP 1 LAST PACK_TYPE C0805
J 0
(-5650 5000);
DISPLAY 0.638298 (-5650 5000);
FORCEPROP 2 LAST CDS_LIB pure_quanta
J 0
(-5700 5200);
DISPLAY INVISIBLE (-5700 5200);
FORCEPROP 1 LAST PATH I36
J 0
(-5650 5350);
DISPLAY 0.978723 (-5650 5350);
PAINT WHITE (-5650 5350);
DISPLAY INVISIBLE (-5650 5350);
FORCEPROP 1 LAST PART_NUMBER CH6104KEA00
J 0
(-5650 5050);
DISPLAY 0.638298 (-5650 5050);
DISPLAY INVISIBLE (-5650 5050);
FORCEADD Q_CAP..1
(-5300 5200);
FORCEPROP 1 LAST LOCATION C2257
J 0
(-5250 5300);
DISPLAY 0.787234 (-5250 5300);
FORCEPROP 0 LAST $SEC 1
J 0
(-5250 5350);
DISPLAY 0.680851 (-5250 5350);
PAINT MONO (-5250 5350);
DISPLAY INVISIBLE (-5250 5350);
FORCEPROP 0 LAST CDS_SEC 1
J 0
(-5250 5350);
DISPLAY 1.021277 (-5250 5350);
DISPLAY INVISIBLE (-5250 5350);
FORCEPROP 1 LASTPIN (-5300 5300) $PN 1
J 0
(-5290 5280);
DISPLAY 0.787234 (-5290 5280);
PAINT MONO (-5290 5280);
FORCEPROP 1 LASTPIN (-5300 5100) $PN 2
J 0
(-5290 5080);
DISPLAY 0.787234 (-5290 5080);
PAINT MONO (-5290 5080);
FORCEPROP 1 LAST PACK_TYPE 0402
J 0
(-5250 5050);
DISPLAY 0.638298 (-5250 5050);
FORCEPROP 1 LAST TOLERANCE 10%
J 0
(-5250 5150);
DISPLAY 0.638298 (-5250 5150);
FORCEPROP 1 LAST MATERIAL X7R
J 0
(-5250 5100);
DISPLAY 0.638298 (-5250 5100);
FORCEPROP 1 LAST VALUE 0.1UF
J 0
(-5250 5250);
DISPLAY 0.638298 (-5250 5250);
FORCEPROP 1 LAST VOLTAGE 25V
J 0
(-5250 5200);
DISPLAY 0.638298 (-5250 5200);
FORCEPROP 2 LAST CDS_LIB pure_quanta
J 0
(-5300 5200);
DISPLAY INVISIBLE (-5300 5200);
FORCEPROP 1 LAST PATH I37
J 0
(-5250 5350);
DISPLAY 0.978723 (-5250 5350);
PAINT WHITE (-5250 5350);
DISPLAY INVISIBLE (-5250 5350);
FORCEPROP 1 LAST PART_NUMBER CH4104K1B00
J 0
(-5250 5050);
DISPLAY 0.808511 (-5250 5050);
DISPLAY INVISIBLE (-5250 5050);
FORCEADD UNIVERSAL_POWER..1
(-5300 5550);
FORCEPROP 3 LASTPIN (-5300 5500) SIG_NAME VFG3P3_CLK_GEN\g
J 0
(-5290 5510);
DISPLAY 0.659574 (-5290 5510);
PAINT MONO (-5290 5510);
DISPLAY INVISIBLE (-5290 5510);
FORCEPROP 1 LAST HDL_POWER VFG3P3_CLK_GEN
J 1
(-5300 5600);
DISPLAY 0.872340 (-5300 5600);
PAINT GREEN (-5300 5600);
FORCEPROP 2 LAST CDS_LIB pure_quanta_power
J 0
(-5300 5550);
DISPLAY INVISIBLE (-5300 5550);
FORCEPROP 1 LAST PATH I38
J 0
(-5250 5575);
DISPLAY 0.872340 (-5250 5575);
PAINT AQUA (-5250 5575);
DISPLAY INVISIBLE (-5250 5575);
FORCEADD UNIVERSAL_GND..1
(-4500 4850);
FORCEPROP 3 LASTPIN (-4500 4900) SIG_NAME GND\g
J 0
(-4490 4910);
DISPLAY 0.659574 (-4490 4910);
PAINT MONO (-4490 4910);
DISPLAY INVISIBLE (-4490 4910);
FORCEPROP 2 LAST CDS_LIB pure_quanta_power
J 0
(-4500 4850);
DISPLAY INVISIBLE (-4500 4850);
FORCEPROP 1 LAST HDL_POWER GND
J 1
(-4475 4775);
DISPLAY 0.872340 (-4475 4775);
PAINT GREEN (-4475 4775);
DISPLAY INVISIBLE (-4475 4775);
FORCEPROP 1 LAST PATH I39
J 0
(-4425 4850);
DISPLAY 0.872340 (-4425 4850);
PAINT AQUA (-4425 4850);
DISPLAY INVISIBLE (-4425 4850);
FORCEADD OFFPAGE..1
(-7675 1500);
FORCEPROP 2 LAST $XR0 127 
J 0
(-7927 1500);
DISPLAY 0.638298 (-7927 1500);
PAINT MONO (-7927 1500);
FORCEPROP 2 LAST CDS_LIB standard
J 0
(-7675 1500);
DISPLAY INVISIBLE (-7675 1500);
FORCEPROP 1 LAST OFFPAGE TRUE
J 0
(-7350 1375);
DISPLAY 0.872340 (-7350 1375);
PAINT GREEN (-7350 1375);
DISPLAY INVISIBLE (-7350 1375);
FORCEPROP 1 LAST COMMENT_BODY TRUE
J 0
(-7550 1400);
DISPLAY 0.872340 (-7550 1400);
PAINT GREEN (-7550 1400);
DISPLAY INVISIBLE (-7550 1400);
FORCEPROP 2 LAST PATH I4
J 0
(-7950 1550);
DISPLAY 0.680851 (-7950 1550);
DISPLAY INVISIBLE (-7950 1550);
FORCEADD Q_CAP..1
(-4975 5200);
FORCEPROP 1 LAST LOCATION C1886
J 0
(-4925 5300);
DISPLAY 0.638298 (-4925 5300);
FORCEPROP 0 LAST $SEC 1
J 0
(-4925 5350);
DISPLAY 0.680851 (-4925 5350);
PAINT MONO (-4925 5350);
DISPLAY INVISIBLE (-4925 5350);
FORCEPROP 0 LAST CDS_SEC 1
J 0
(-4925 5350);
DISPLAY 1.021277 (-4925 5350);
DISPLAY INVISIBLE (-4925 5350);
FORCEPROP 1 LASTPIN (-4975 5300) $PN 1
J 0
(-4965 5280);
DISPLAY 0.787234 (-4965 5280);
PAINT MONO (-4965 5280);
FORCEPROP 1 LASTPIN (-4975 5100) $PN 2
J 0
(-4965 5080);
DISPLAY 0.787234 (-4965 5080);
PAINT MONO (-4965 5080);
FORCEPROP 1 LAST VALUE 0.1UF
J 0
(-4925 5250);
DISPLAY 0.638298 (-4925 5250);
FORCEPROP 1 LAST VOLTAGE 25V
J 0
(-4925 5200);
DISPLAY 0.638298 (-4925 5200);
FORCEPROP 1 LAST TOLERANCE 10%
J 0
(-4925 5150);
DISPLAY 0.638298 (-4925 5150);
FORCEPROP 1 LAST MATERIAL X7R
J 0
(-4925 5100);
DISPLAY 0.638298 (-4925 5100);
FORCEPROP 1 LAST PACK_TYPE 0402
J 0
(-4925 5050);
DISPLAY 0.638298 (-4925 5050);
FORCEPROP 2 LAST CDS_LIB pure_quanta
J 0
(-4975 5200);
DISPLAY INVISIBLE (-4975 5200);
FORCEPROP 1 LAST PATH I40
J 0
(-4925 5350);
DISPLAY 0.978723 (-4925 5350);
PAINT WHITE (-4925 5350);
DISPLAY INVISIBLE (-4925 5350);
FORCEPROP 1 LAST PART_NUMBER CH4104K1B00
J 0
(-4925 5050);
DISPLAY 0.808511 (-4925 5050);
DISPLAY INVISIBLE (-4925 5050);
FORCEADD Q_CAP..1
(-4750 5200);
FORCEPROP 1 LAST LOCATION C1889
J 0
(-4700 5300);
DISPLAY 0.638298 (-4700 5300);
FORCEPROP 0 LAST $SEC 1
J 0
(-4700 5350);
DISPLAY 0.680851 (-4700 5350);
PAINT MONO (-4700 5350);
DISPLAY INVISIBLE (-4700 5350);
FORCEPROP 0 LAST CDS_SEC 1
J 0
(-4700 5350);
DISPLAY 1.021277 (-4700 5350);
DISPLAY INVISIBLE (-4700 5350);
FORCEPROP 1 LASTPIN (-4750 5300) $PN 1
J 0
(-4740 5280);
DISPLAY 0.787234 (-4740 5280);
PAINT MONO (-4740 5280);
FORCEPROP 1 LASTPIN (-4750 5100) $PN 2
J 0
(-4740 5080);
DISPLAY 0.787234 (-4740 5080);
PAINT MONO (-4740 5080);
FORCEPROP 1 LAST VOLTAGE 25V
J 0
(-4700 5200);
DISPLAY 0.638298 (-4700 5200);
FORCEPROP 1 LAST VALUE 0.1UF
J 0
(-4700 5250);
DISPLAY 0.638298 (-4700 5250);
FORCEPROP 1 LAST TOLERANCE 10%
J 0
(-4700 5150);
DISPLAY 0.638298 (-4700 5150);
FORCEPROP 1 LAST MATERIAL X7R
J 0
(-4700 5100);
DISPLAY 0.638298 (-4700 5100);
FORCEPROP 1 LAST PACK_TYPE 0402
J 0
(-4700 5050);
DISPLAY 0.638298 (-4700 5050);
FORCEPROP 2 LAST CDS_LIB pure_quanta
J 0
(-4750 5200);
DISPLAY INVISIBLE (-4750 5200);
FORCEPROP 1 LAST PATH I41
J 0
(-4700 5350);
DISPLAY 0.978723 (-4700 5350);
PAINT WHITE (-4700 5350);
DISPLAY INVISIBLE (-4700 5350);
FORCEPROP 1 LAST PART_NUMBER CH4104K1B00
J 0
(-4700 5050);
DISPLAY 0.808511 (-4700 5050);
DISPLAY INVISIBLE (-4700 5050);
FORCEADD Q_CAP..1
(-4500 5200);
FORCEPROP 1 LAST LOCATION C95
J 0
(-4450 5300);
DISPLAY 0.638298 (-4450 5300);
FORCEPROP 0 LAST $SEC 1
J 0
(-4450 5350);
DISPLAY 0.680851 (-4450 5350);
PAINT MONO (-4450 5350);
DISPLAY INVISIBLE (-4450 5350);
FORCEPROP 0 LAST CDS_SEC 1
J 0
(-4450 5350);
DISPLAY 1.021277 (-4450 5350);
DISPLAY INVISIBLE (-4450 5350);
FORCEPROP 1 LASTPIN (-4500 5300) $PN 1
J 0
(-4490 5280);
DISPLAY 0.787234 (-4490 5280);
PAINT MONO (-4490 5280);
FORCEPROP 1 LASTPIN (-4500 5100) $PN 2
J 0
(-4490 5080);
DISPLAY 0.787234 (-4490 5080);
PAINT MONO (-4490 5080);
FORCEPROP 1 LAST VOLTAGE 25V
J 0
(-4450 5200);
DISPLAY 0.638298 (-4450 5200);
FORCEPROP 1 LAST TOLERANCE 10%
J 0
(-4450 5150);
DISPLAY 0.638298 (-4450 5150);
FORCEPROP 1 LAST MATERIAL X7R
J 0
(-4450 5100);
DISPLAY 0.638298 (-4450 5100);
FORCEPROP 1 LAST VALUE 0.1UF
J 0
(-4450 5250);
DISPLAY 0.638298 (-4450 5250);
FORCEPROP 1 LAST PACK_TYPE 0402
J 0
(-4450 5050);
DISPLAY 0.638298 (-4450 5050);
FORCEPROP 2 LAST CDS_LIB pure_quanta
J 0
(-4500 5200);
DISPLAY INVISIBLE (-4500 5200);
FORCEPROP 1 LAST PATH I42
J 0
(-4450 5350);
DISPLAY 0.978723 (-4450 5350);
PAINT WHITE (-4450 5350);
DISPLAY INVISIBLE (-4450 5350);
FORCEPROP 1 LAST PART_NUMBER CH4104K1B00
J 0
(-4450 5050);
DISPLAY 0.808511 (-4450 5050);
DISPLAY INVISIBLE (-4450 5050);
FORCEADD Q_RES..1
(-4175 5400);
FORCEPROP 1 LAST LOCATION R4077
J 0
(-4300 5400);
DISPLAY 0.638298 (-4300 5400);
FORCEPROP 0 LAST $SEC 1
J 0
(-4300 5450);
DISPLAY 0.680851 (-4300 5450);
PAINT MONO (-4300 5450);
DISPLAY INVISIBLE (-4300 5450);
FORCEPROP 0 LAST CDS_SEC 1
J 0
(-4300 5450);
DISPLAY 1.021277 (-4300 5450);
DISPLAY INVISIBLE (-4300 5450);
FORCEPROP 1 LASTPIN (-4275 5400) $PN 1
J 0
(-4263 5412);
DISPLAY 0.787234 (-4263 5412);
PAINT MONO (-4263 5412);
FORCEPROP 1 LASTPIN (-4075 5400) $PN 2
J 0
(-4113 5412);
DISPLAY 0.787234 (-4113 5412);
PAINT MONO (-4113 5412);
FORCEPROP 1 LAST PACK_TYPE 0402LF
J 0
(-4150 5300);
DISPLAY 0.510638 (-4150 5300);
FORCEPROP 1 LAST WATTAGE 1/16W
J 2
(-4175 5300);
DISPLAY 0.510638 (-4175 5300);
FORCEPROP 1 LAST MATERIAL CHIP
J 0
(-4050 5400);
DISPLAY 0.510638 (-4050 5400);
FORCEPROP 1 LAST TOLERANCE 1%
J 0
(-4150 5350);
DISPLAY 0.510638 (-4150 5350);
FORCEPROP 1 LAST VALUE 1
J 2
(-4175 5350);
DISPLAY 0.510638 (-4175 5350);
FORCEPROP 2 LAST CDS_LIB pure_quanta
J 0
(-4175 5400);
DISPLAY INVISIBLE (-4175 5400);
FORCEPROP 1 LAST PATH I43
J 0
(-4225 5550);
DISPLAY 0.978723 (-4225 5550);
PAINT WHITE (-4225 5550);
DISPLAY INVISIBLE (-4225 5550);
FORCEPROP 1 LAST PART_NUMBER CS-1002FB04
J 0
(-4275 5275);
DISPLAY 0.510638 (-4275 5275);
DISPLAY INVISIBLE (-4275 5275);
FORCEADD OFFPAGE..2
(-3775 1450);
FORCEPROP 2 LAST $XR2 234 
J 0
(-3346 1450);
DISPLAY 0.638298 (-3346 1450);
PAINT MONO (-3346 1450);
FORCEPROP 2 LAST $XR1 112 
J 0
(-3466 1450);
DISPLAY 0.638298 (-3466 1450);
PAINT MONO (-3466 1450);
FORCEPROP 2 LAST $XR0 111 
J 0
(-3586 1450);
DISPLAY 0.638298 (-3586 1450);
PAINT MONO (-3586 1450);
FORCEPROP 2 LAST CDS_LIB standard
J 2
(-3775 1450);
DISPLAY INVISIBLE (-3775 1450);
FORCEPROP 1 LAST OFFPAGE TRUE
J 0
(-3450 1325);
DISPLAY 0.872340 (-3450 1325);
PAINT GREEN (-3450 1325);
DISPLAY INVISIBLE (-3450 1325);
FORCEPROP 1 LAST COMMENT_BODY TRUE
J 0
(-3820 1355);
DISPLAY 0.872340 (-3820 1355);
PAINT GREEN (-3820 1355);
DISPLAY INVISIBLE (-3820 1355);
FORCEPROP 2 LAST PATH I44
J 0
(-3450 1500);
DISPLAY 0.680851 (-3450 1500);
DISPLAY INVISIBLE (-3450 1500);
FORCEADD UNIVERSAL_GND..1
(-2650 925);
FORCEPROP 3 LASTPIN (-2650 975) SIG_NAME GND\g
J 0
(-2640 985);
DISPLAY 0.659574 (-2640 985);
PAINT MONO (-2640 985);
DISPLAY INVISIBLE (-2640 985);
FORCEPROP 2 LAST CDS_LIB pure_quanta_power
J 0
(-2650 925);
DISPLAY INVISIBLE (-2650 925);
FORCEPROP 1 LAST HDL_POWER GND
J 1
(-2625 850);
DISPLAY 0.872340 (-2625 850);
PAINT GREEN (-2625 850);
DISPLAY INVISIBLE (-2625 850);
FORCEPROP 1 LAST PATH I45
J 0
(-2575 925);
DISPLAY 0.872340 (-2575 925);
PAINT AQUA (-2575 925);
DISPLAY INVISIBLE (-2575 925);
FORCEADD Q_RES..2
R 2
(-2650 1200);
FORCEPROP 1 LAST LOCATION R4079
J 2
(-2695 1325);
DISPLAY 0.638298 (-2695 1325);
FORCEPROP 0 LAST $SEC 1
J 0
(-2675 1375);
DISPLAY 0.680851 (-2675 1375);
PAINT MONO (-2675 1375);
DISPLAY INVISIBLE (-2675 1375);
FORCEPROP 0 LAST CDS_SEC 1
J 0
(-2675 1375);
DISPLAY 1.021277 (-2675 1375);
DISPLAY INVISIBLE (-2675 1375);
FORCEPROP 1 LASTPIN (-2650 1300) $PN 1
J 2
(-2655 1262);
DISPLAY 0.787234 (-2655 1262);
PAINT MONO (-2655 1262);
FORCEPROP 1 LASTPIN (-2650 1100) $PN 2
J 2
(-2655 1110);
DISPLAY 0.787234 (-2655 1110);
PAINT MONO (-2655 1110);
FORCEPROP 1 LAST VALUE 10K
J 2
(-2695 1275);
DISPLAY 0.638298 (-2695 1275);
FORCEPROP 1 LAST TOLERANCE 1%
J 2
(-2695 1225);
DISPLAY 0.638298 (-2695 1225);
FORCEPROP 1 LAST PACK_TYPE 0402LF
J 2
(-2690 1075);
DISPLAY 0.638298 (-2690 1075);
FORCEPROP 1 LAST WATTAGE 1/16W
J 2
(-2690 1175);
DISPLAY 0.638298 (-2690 1175);
FORCEPROP 1 LAST MATERIAL CHIP
J 2
(-2690 1125);
DISPLAY 0.638298 (-2690 1125);
FORCEPROP 2 LAST CDS_LIB pure_quanta
J 0
(-2650 1200);
DISPLAY INVISIBLE (-2650 1200);
FORCEPROP 1 LAST PATH I46
J 2
(-2700 1375);
DISPLAY 0.978723 (-2700 1375);
PAINT WHITE (-2700 1375);
DISPLAY INVISIBLE (-2700 1375);
FORCEPROP 1 LAST PART_NUMBER CS31002FB08
J 2
(-2690 1025);
DISPLAY 0.638298 (-2690 1025);
DISPLAY INVISIBLE (-2690 1025);
FORCEADD Q_RES..2
R 2
(-2650 1675);
FORCEPROP 1 LAST LOCATION R4078
J 2
(-2695 1800);
DISPLAY 0.638298 (-2695 1800);
FORCEPROP 0 LAST $SEC 1
J 0
(-2675 1850);
DISPLAY 0.680851 (-2675 1850);
PAINT MONO (-2675 1850);
DISPLAY INVISIBLE (-2675 1850);
FORCEPROP 0 LAST CDS_SEC 1
J 0
(-2675 1850);
DISPLAY 1.021277 (-2675 1850);
DISPLAY INVISIBLE (-2675 1850);
FORCEPROP 1 LASTPIN (-2650 1775) $PN 1
J 2
(-2655 1737);
DISPLAY 0.787234 (-2655 1737);
PAINT MONO (-2655 1737);
FORCEPROP 1 LASTPIN (-2650 1575) $PN 2
J 2
(-2655 1585);
DISPLAY 0.787234 (-2655 1585);
PAINT MONO (-2655 1585);
FORCEPROP 1 LAST MATERIAL EMPTY
J 2
(-2690 1600);
DISPLAY 0.638298 (-2690 1600);
PAINT RED (-2690 1600);
FORCEPROP 1 LAST TOLERANCE 1%
J 2
(-2695 1700);
DISPLAY 0.638298 (-2695 1700);
FORCEPROP 1 LAST VALUE 10K
J 2
(-2695 1750);
DISPLAY 0.638298 (-2695 1750);
FORCEPROP 1 LAST WATTAGE 1/16W
J 2
(-2690 1650);
DISPLAY 0.638298 (-2690 1650);
FORCEPROP 1 LAST PACK_TYPE 0402LF
J 2
(-2690 1550);
DISPLAY 0.638298 (-2690 1550);
FORCEPROP 2 LAST CDS_LIB pure_quanta
J 0
(-2650 1675);
DISPLAY INVISIBLE (-2650 1675);
FORCEPROP 1 LAST PATH I47
J 2
(-2700 1850);
DISPLAY 0.978723 (-2700 1850);
PAINT WHITE (-2700 1850);
DISPLAY INVISIBLE (-2700 1850);
FORCEPROP 1 LAST PART_NUMBER CS31002FB08
J 2
(-2690 1500);
DISPLAY 0.638298 (-2690 1500);
DISPLAY INVISIBLE (-2690 1500);
FORCEADD UNIVERSAL_POWER..1
(-2650 1950);
FORCEPROP 3 LASTPIN (-2650 1900) SIG_NAME P3V3_AUX\g
J 0
(-2640 1910);
DISPLAY 0.659574 (-2640 1910);
PAINT MONO (-2640 1910);
DISPLAY INVISIBLE (-2640 1910);
FORCEPROP 1 LAST HDL_POWER P3V3_AUX
J 1
(-2650 2000);
DISPLAY 0.872340 (-2650 2000);
PAINT GREEN (-2650 2000);
FORCEPROP 2 LAST CDS_LIB pure_quanta_power
J 0
(-2650 1950);
DISPLAY INVISIBLE (-2650 1950);
FORCEPROP 1 LAST PATH I48
J 0
(-2600 1975);
DISPLAY 0.872340 (-2600 1975);
PAINT AQUA (-2600 1975);
DISPLAY INVISIBLE (-2600 1975);
FORCEADD OFFPAGE..2
(-1950 1425);
FORCEPROP 2 LAST $XR0 234 
J 0
(-1761 1425);
DISPLAY 0.638298 (-1761 1425);
PAINT MONO (-1761 1425);
FORCEPROP 2 LAST CDS_LIB standard
J 0
(-1950 1425);
DISPLAY INVISIBLE (-1950 1425);
FORCEPROP 1 LAST OFFPAGE TRUE
J 0
(-1625 1300);
DISPLAY 0.872340 (-1625 1300);
DISPLAY INVISIBLE (-1625 1300);
FORCEPROP 1 LAST COMMENT_BODY TRUE
J 0
(-1995 1330);
DISPLAY 0.872340 (-1995 1330);
PAINT GREEN (-1995 1330);
DISPLAY INVISIBLE (-1995 1330);
FORCEPROP 2 LAST PATH I49
J 0
(-1750 1475);
DISPLAY 0.680851 (-1750 1475);
DISPLAY INVISIBLE (-1750 1475);
FORCEADD UNIVERSAL_GND..1
(-6300 725);
FORCEPROP 3 LASTPIN (-6300 775) SIG_NAME GND\g
J 0
(-6290 785);
DISPLAY 0.659574 (-6290 785);
PAINT MONO (-6290 785);
DISPLAY INVISIBLE (-6290 785);
FORCEPROP 2 LAST CDS_LIB pure_quanta_power
J 0
(-6300 725);
DISPLAY INVISIBLE (-6300 725);
FORCEPROP 1 LAST HDL_POWER GND
J 1
(-6275 650);
DISPLAY 0.872340 (-6275 650);
PAINT GREEN (-6275 650);
DISPLAY INVISIBLE (-6275 650);
FORCEPROP 1 LAST PATH I5
J 0
(-6225 725);
DISPLAY 0.872340 (-6225 725);
PAINT AQUA (-6225 725);
DISPLAY INVISIBLE (-6225 725);
FORCEADD Q_RES..1
(-2725 3750);
FORCEPROP 1 LAST LOCATION R3338
J 0
(-2950 3750);
DISPLAY 0.638298 (-2950 3750);
FORCEPROP 0 LAST $SEC 1
J 0
(-2775 3850);
DISPLAY 0.680851 (-2775 3850);
PAINT MONO (-2775 3850);
DISPLAY INVISIBLE (-2775 3850);
FORCEPROP 0 LAST CDS_SEC 1
J 0
(-2775 3850);
DISPLAY 1.021277 (-2775 3850);
DISPLAY INVISIBLE (-2775 3850);
FORCEPROP 1 LASTPIN (-2825 3750) $PN 1
J 0
(-2813 3762);
DISPLAY 0.787234 (-2813 3762);
PAINT MONO (-2813 3762);
FORCEPROP 1 LASTPIN (-2625 3750) $PN 2
J 0
(-2663 3762);
DISPLAY 0.787234 (-2663 3762);
PAINT MONO (-2663 3762);
FORCEPROP 1 LAST WATTAGE 1/16W
J 2
(-2650 3575);
DISPLAY 0.638298 (-2650 3575);
FORCEPROP 1 LAST PACK_TYPE 0402LF
J 0
(-2850 3625);
DISPLAY 0.638298 (-2850 3625);
FORCEPROP 1 LAST VALUE 0
J 2
(-2575 3750);
DISPLAY 0.787234 (-2575 3750);
FORCEPROP 1 LAST MATERIAL CHIP
J 0
(-2550 3750);
DISPLAY 0.638298 (-2550 3750);
FORCEPROP 1 LAST TOLERANCE 5%
J 0
(-2650 3625);
DISPLAY 0.638298 (-2650 3625);
FORCEPROP 2 LAST CDS_LIB pure_quanta
J 0
(-2725 3750);
DISPLAY INVISIBLE (-2725 3750);
FORCEPROP 1 LAST PATH I50
J 0
(-2775 3900);
DISPLAY 0.978723 (-2775 3900);
PAINT WHITE (-2775 3900);
DISPLAY INVISIBLE (-2775 3900);
FORCEPROP 1 LAST PART_NUMBER CS00002JB13
J 0
(-2875 3675);
DISPLAY 0.638298 (-2875 3675);
DISPLAY INVISIBLE (-2875 3675);
FORCEADD Q_RES..1
(-2725 3800);
FORCEPROP 1 LAST LOCATION R3337
J 0
(-2950 3800);
DISPLAY 0.638298 (-2950 3800);
FORCEPROP 0 LAST $SEC 1
J 0
(-2775 3900);
DISPLAY 0.680851 (-2775 3900);
PAINT MONO (-2775 3900);
DISPLAY INVISIBLE (-2775 3900);
FORCEPROP 0 LAST CDS_SEC 1
J 0
(-2775 3900);
DISPLAY 1.021277 (-2775 3900);
DISPLAY INVISIBLE (-2775 3900);
FORCEPROP 1 LASTPIN (-2825 3800) $PN 1
J 0
(-2813 3812);
DISPLAY 0.787234 (-2813 3812);
PAINT MONO (-2813 3812);
FORCEPROP 1 LASTPIN (-2625 3800) $PN 2
J 0
(-2663 3812);
DISPLAY 0.787234 (-2663 3812);
PAINT MONO (-2663 3812);
FORCEPROP 1 LAST MATERIAL CHIP
J 0
(-2550 3800);
DISPLAY 0.638298 (-2550 3800);
FORCEPROP 1 LAST VALUE 0
J 2
(-2575 3800);
DISPLAY 0.787234 (-2575 3800);
FORCEPROP 2 LAST CDS_LIB pure_quanta
J 0
(-2725 3800);
DISPLAY INVISIBLE (-2725 3800);
FORCEPROP 1 LAST WATTAGE 1/16W
J 2
(-2250 3900);
DISPLAY 0.638298 (-2250 3900);
DISPLAY INVISIBLE (-2250 3900);
FORCEPROP 1 LAST TOLERANCE 5%
J 0
(-2425 3800);
DISPLAY 0.638298 (-2425 3800);
DISPLAY INVISIBLE (-2425 3800);
FORCEPROP 1 LAST PACK_TYPE 0402LF
J 0
(-2325 3800);
DISPLAY 0.638298 (-2325 3800);
DISPLAY INVISIBLE (-2325 3800);
FORCEPROP 1 LAST PATH I51
J 0
(-2775 3950);
DISPLAY 0.978723 (-2775 3950);
PAINT WHITE (-2775 3950);
DISPLAY INVISIBLE (-2775 3950);
FORCEPROP 1 LAST PART_NUMBER CS00002JB13
J 0
(-2600 3850);
DISPLAY 0.638298 (-2600 3850);
DISPLAY INVISIBLE (-2600 3850);
FORCEADD Q_RES..1
(-2725 3900);
FORCEPROP 1 LAST LOCATION R3336
J 0
(-2950 3900);
DISPLAY 0.638298 (-2950 3900);
FORCEPROP 0 LAST $SEC 1
J 0
(-2775 4000);
DISPLAY 0.680851 (-2775 4000);
PAINT MONO (-2775 4000);
DISPLAY INVISIBLE (-2775 4000);
FORCEPROP 0 LAST CDS_SEC 1
J 0
(-2775 4000);
DISPLAY 1.021277 (-2775 4000);
DISPLAY INVISIBLE (-2775 4000);
FORCEPROP 1 LASTPIN (-2825 3900) $PN 1
J 0
(-2813 3912);
DISPLAY 0.787234 (-2813 3912);
PAINT MONO (-2813 3912);
FORCEPROP 1 LASTPIN (-2625 3900) $PN 2
J 0
(-2663 3912);
DISPLAY 0.787234 (-2663 3912);
PAINT MONO (-2663 3912);
FORCEPROP 1 LAST MATERIAL CHIP
J 0
(-2550 3900);
DISPLAY 0.638298 (-2550 3900);
FORCEPROP 1 LAST VALUE 0
J 2
(-2575 3900);
DISPLAY 0.787234 (-2575 3900);
FORCEPROP 2 LAST CDS_LIB pure_quanta
J 0
(-2725 3900);
DISPLAY INVISIBLE (-2725 3900);
FORCEPROP 1 LAST PACK_TYPE 0402LF
J 0
(-2325 3900);
DISPLAY 0.638298 (-2325 3900);
DISPLAY INVISIBLE (-2325 3900);
FORCEPROP 1 LAST TOLERANCE 5%
J 0
(-2425 3900);
DISPLAY 0.638298 (-2425 3900);
DISPLAY INVISIBLE (-2425 3900);
FORCEPROP 1 LAST WATTAGE 1/16W
J 2
(-2250 4000);
DISPLAY 0.638298 (-2250 4000);
DISPLAY INVISIBLE (-2250 4000);
FORCEPROP 1 LAST PATH I52
J 0
(-2775 4050);
DISPLAY 0.978723 (-2775 4050);
PAINT WHITE (-2775 4050);
DISPLAY INVISIBLE (-2775 4050);
FORCEPROP 1 LAST PART_NUMBER CS00002JB13
J 0
(-2600 3950);
DISPLAY 0.638298 (-2600 3950);
DISPLAY INVISIBLE (-2600 3950);
FORCEADD Q_RES..1
(-2725 3950);
FORCEPROP 1 LAST LOCATION R3335
J 0
(-2950 3950);
DISPLAY 0.638298 (-2950 3950);
FORCEPROP 0 LAST $SEC 1
J 0
(-2775 4050);
DISPLAY 0.680851 (-2775 4050);
PAINT MONO (-2775 4050);
DISPLAY INVISIBLE (-2775 4050);
FORCEPROP 0 LAST CDS_SEC 1
J 0
(-2775 4050);
DISPLAY 1.021277 (-2775 4050);
DISPLAY INVISIBLE (-2775 4050);
FORCEPROP 1 LASTPIN (-2825 3950) $PN 1
J 0
(-2813 3962);
DISPLAY 0.787234 (-2813 3962);
PAINT MONO (-2813 3962);
FORCEPROP 1 LASTPIN (-2625 3950) $PN 2
J 0
(-2663 3962);
DISPLAY 0.787234 (-2663 3962);
PAINT MONO (-2663 3962);
FORCEPROP 1 LAST VALUE 0
J 2
(-2575 3950);
DISPLAY 0.787234 (-2575 3950);
FORCEPROP 1 LAST MATERIAL CHIP
J 0
(-2550 3950);
DISPLAY 0.638298 (-2550 3950);
FORCEPROP 1 LAST PACK_TYPE 0402LF
J 0
(-2325 3950);
DISPLAY 0.638298 (-2325 3950);
DISPLAY INVISIBLE (-2325 3950);
FORCEPROP 1 LAST TOLERANCE 5%
J 0
(-2425 3950);
DISPLAY 0.638298 (-2425 3950);
DISPLAY INVISIBLE (-2425 3950);
FORCEPROP 1 LAST WATTAGE 1/16W
J 2
(-2250 4050);
DISPLAY 0.638298 (-2250 4050);
DISPLAY INVISIBLE (-2250 4050);
FORCEPROP 2 LAST CDS_LIB pure_quanta
J 0
(-2725 3950);
DISPLAY INVISIBLE (-2725 3950);
FORCEPROP 1 LAST PATH I53
J 0
(-2775 4100);
DISPLAY 0.978723 (-2775 4100);
PAINT WHITE (-2775 4100);
DISPLAY INVISIBLE (-2775 4100);
FORCEPROP 1 LAST PART_NUMBER CS00002JB13
J 0
(-2600 4000);
DISPLAY 0.638298 (-2600 4000);
DISPLAY INVISIBLE (-2600 4000);
FORCEADD UNIVERSAL_GND..1
(-1325 950);
FORCEPROP 3 LASTPIN (-1325 1000) SIG_NAME GND\g
J 0
(-1315 1010);
DISPLAY 0.659574 (-1315 1010);
PAINT MONO (-1315 1010);
DISPLAY INVISIBLE (-1315 1010);
FORCEPROP 2 LAST CDS_LIB pure_quanta_power
J 0
(-1325 950);
DISPLAY INVISIBLE (-1325 950);
FORCEPROP 1 LAST HDL_POWER GND
J 1
(-1300 875);
DISPLAY 0.872340 (-1300 875);
PAINT GREEN (-1300 875);
DISPLAY INVISIBLE (-1300 875);
FORCEPROP 1 LAST PATH I54
J 0
(-1250 950);
DISPLAY 0.872340 (-1250 950);
PAINT AQUA (-1250 950);
DISPLAY INVISIBLE (-1250 950);
FORCEADD Q_RES..2
R 2
(-1325 1225);
FORCEPROP 1 LAST LOCATION R4082
J 2
(-1370 1350);
DISPLAY 0.638298 (-1370 1350);
FORCEPROP 0 LAST $SEC 1
J 0
(-1350 1400);
DISPLAY 0.680851 (-1350 1400);
PAINT MONO (-1350 1400);
DISPLAY INVISIBLE (-1350 1400);
FORCEPROP 0 LAST CDS_SEC 1
J 0
(-1350 1400);
DISPLAY 1.021277 (-1350 1400);
DISPLAY INVISIBLE (-1350 1400);
FORCEPROP 1 LASTPIN (-1325 1325) $PN 1
J 2
(-1330 1287);
DISPLAY 0.787234 (-1330 1287);
PAINT MONO (-1330 1287);
FORCEPROP 1 LASTPIN (-1325 1125) $PN 2
J 2
(-1330 1135);
DISPLAY 0.787234 (-1330 1135);
PAINT MONO (-1330 1135);
FORCEPROP 1 LAST VALUE 10K
J 2
(-1370 1300);
DISPLAY 0.638298 (-1370 1300);
FORCEPROP 1 LAST MATERIAL EMPTY
J 2
(-1365 1150);
DISPLAY 0.638298 (-1365 1150);
PAINT RED (-1365 1150);
FORCEPROP 1 LAST WATTAGE 1/16W
J 2
(-1365 1200);
DISPLAY 0.638298 (-1365 1200);
FORCEPROP 1 LAST TOLERANCE 1%
J 2
(-1370 1250);
DISPLAY 0.638298 (-1370 1250);
FORCEPROP 1 LAST PACK_TYPE 0402LF
J 2
(-1365 1100);
DISPLAY 0.638298 (-1365 1100);
FORCEPROP 2 LAST CDS_LIB pure_quanta
J 0
(-1325 1225);
DISPLAY INVISIBLE (-1325 1225);
FORCEPROP 1 LAST PATH I55
J 2
(-1375 1400);
DISPLAY 0.978723 (-1375 1400);
PAINT WHITE (-1375 1400);
DISPLAY INVISIBLE (-1375 1400);
FORCEPROP 1 LAST PART_NUMBER CS31002FB08
J 2
(-1365 1050);
DISPLAY 0.638298 (-1365 1050);
DISPLAY INVISIBLE (-1365 1050);
FORCEADD Q_RES..2
R 2
(-1325 1700);
FORCEPROP 1 LAST LOCATION R4081
J 2
(-1370 1825);
DISPLAY 0.638298 (-1370 1825);
FORCEPROP 0 LAST $SEC 1
J 0
(-1350 1875);
DISPLAY 0.680851 (-1350 1875);
PAINT MONO (-1350 1875);
DISPLAY INVISIBLE (-1350 1875);
FORCEPROP 0 LAST CDS_SEC 1
J 0
(-1350 1875);
DISPLAY 1.021277 (-1350 1875);
DISPLAY INVISIBLE (-1350 1875);
FORCEPROP 1 LASTPIN (-1325 1800) $PN 1
J 2
(-1330 1762);
DISPLAY 0.787234 (-1330 1762);
PAINT MONO (-1330 1762);
FORCEPROP 1 LASTPIN (-1325 1600) $PN 2
J 2
(-1330 1610);
DISPLAY 0.787234 (-1330 1610);
PAINT MONO (-1330 1610);
FORCEPROP 1 LAST WATTAGE 1/16W
J 2
(-1365 1675);
DISPLAY 0.638298 (-1365 1675);
FORCEPROP 1 LAST TOLERANCE 1%
J 2
(-1370 1725);
DISPLAY 0.638298 (-1370 1725);
FORCEPROP 1 LAST VALUE 10K
J 2
(-1370 1775);
DISPLAY 0.638298 (-1370 1775);
FORCEPROP 1 LAST PACK_TYPE 0402LF
J 2
(-1365 1575);
DISPLAY 0.638298 (-1365 1575);
FORCEPROP 1 LAST MATERIAL CHIP
J 2
(-1365 1625);
DISPLAY 0.638298 (-1365 1625);
FORCEPROP 2 LAST CDS_LIB pure_quanta
J 0
(-1325 1700);
DISPLAY INVISIBLE (-1325 1700);
FORCEPROP 1 LAST PATH I56
J 2
(-1375 1875);
DISPLAY 0.978723 (-1375 1875);
PAINT WHITE (-1375 1875);
DISPLAY INVISIBLE (-1375 1875);
FORCEPROP 1 LAST PART_NUMBER CS31002FB08
J 2
(-1365 1525);
DISPLAY 0.638298 (-1365 1525);
DISPLAY INVISIBLE (-1365 1525);
FORCEADD UNIVERSAL_POWER..1
(-1325 1975);
FORCEPROP 3 LASTPIN (-1325 1925) SIG_NAME P3V3_AUX\g
J 0
(-1315 1935);
DISPLAY 0.659574 (-1315 1935);
PAINT MONO (-1315 1935);
DISPLAY INVISIBLE (-1315 1935);
FORCEPROP 1 LAST HDL_POWER P3V3_AUX
J 1
(-1325 2025);
DISPLAY 0.872340 (-1325 2025);
PAINT GREEN (-1325 2025);
FORCEPROP 2 LAST CDS_LIB pure_quanta_power
J 0
(-1325 1975);
DISPLAY INVISIBLE (-1325 1975);
FORCEPROP 1 LAST PATH I57
J 0
(-1275 2000);
DISPLAY 0.872340 (-1275 2000);
PAINT AQUA (-1275 2000);
DISPLAY INVISIBLE (-1275 2000);
FORCEADD OFFPAGE..2
(-625 1450);
FORCEPROP 2 LAST $XR0 234 
J 0
(-436 1450);
DISPLAY 0.638298 (-436 1450);
PAINT MONO (-436 1450);
FORCEPROP 2 LAST CDS_LIB standard
J 0
(-625 1450);
DISPLAY INVISIBLE (-625 1450);
FORCEPROP 1 LAST OFFPAGE TRUE
J 0
(-300 1325);
DISPLAY 0.872340 (-300 1325);
DISPLAY INVISIBLE (-300 1325);
FORCEPROP 1 LAST COMMENT_BODY TRUE
J 0
(-670 1355);
DISPLAY 0.872340 (-670 1355);
PAINT GREEN (-670 1355);
DISPLAY INVISIBLE (-670 1355);
FORCEPROP 2 LAST PATH I58
J 0
(-425 1500);
DISPLAY 0.680851 (-425 1500);
DISPLAY INVISIBLE (-425 1500);
FORCEADD Q_RES..2
R 2
(-1325 2500);
FORCEPROP 1 LAST LOCATION R4080
J 2
(-1370 2625);
DISPLAY 0.638298 (-1370 2625);
FORCEPROP 0 LAST $SEC 1
J 0
(-1350 2675);
DISPLAY 0.680851 (-1350 2675);
PAINT MONO (-1350 2675);
DISPLAY INVISIBLE (-1350 2675);
FORCEPROP 0 LAST CDS_SEC 1
J 0
(-1350 2675);
DISPLAY 1.021277 (-1350 2675);
DISPLAY INVISIBLE (-1350 2675);
FORCEPROP 1 LASTPIN (-1325 2600) $PN 1
J 2
(-1330 2562);
DISPLAY 0.787234 (-1330 2562);
PAINT MONO (-1330 2562);
FORCEPROP 1 LASTPIN (-1325 2400) $PN 2
J 2
(-1330 2410);
DISPLAY 0.787234 (-1330 2410);
PAINT MONO (-1330 2410);
FORCEPROP 1 LAST VALUE 10K
J 2
(-1370 2575);
DISPLAY 0.638298 (-1370 2575);
FORCEPROP 1 LAST TOLERANCE 1%
J 2
(-1370 2525);
DISPLAY 0.638298 (-1370 2525);
FORCEPROP 1 LAST WATTAGE 1/16W
J 2
(-1365 2475);
DISPLAY 0.638298 (-1365 2475);
FORCEPROP 1 LAST MATERIAL CHIP
J 2
(-1365 2425);
DISPLAY 0.638298 (-1365 2425);
FORCEPROP 1 LAST PACK_TYPE 0402LF
J 2
(-1365 2375);
DISPLAY 0.638298 (-1365 2375);
FORCEPROP 2 LAST CDS_LIB pure_quanta
J 0
(-1325 2500);
DISPLAY INVISIBLE (-1325 2500);
FORCEPROP 1 LAST PATH I59
J 2
(-1375 2675);
DISPLAY 0.978723 (-1375 2675);
PAINT WHITE (-1375 2675);
DISPLAY INVISIBLE (-1375 2675);
FORCEPROP 1 LAST PART_NUMBER CS31002FB08
J 2
(-1365 2325);
DISPLAY 0.638298 (-1365 2325);
DISPLAY INVISIBLE (-1365 2325);
FORCEADD Q_RES..1
(-6625 1400);
FORCEPROP 1 LAST LOCATION R3327
J 0
(-6850 1400);
DISPLAY 0.638298 (-6850 1400);
FORCEPROP 0 LAST $SEC 1
J 0
(-6450 1450);
DISPLAY 0.680851 (-6450 1450);
PAINT MONO (-6450 1450);
DISPLAY INVISIBLE (-6450 1450);
FORCEPROP 0 LAST CDS_SEC 1
J 0
(-6450 1450);
DISPLAY 1.021277 (-6450 1450);
DISPLAY INVISIBLE (-6450 1450);
FORCEPROP 1 LASTPIN (-6725 1400) $PN 1
J 0
(-6713 1412);
DISPLAY 0.787234 (-6713 1412);
PAINT MONO (-6713 1412);
FORCEPROP 1 LASTPIN (-6525 1400) $PN 2
J 0
(-6563 1412);
DISPLAY 0.787234 (-6563 1412);
PAINT MONO (-6563 1412);
FORCEPROP 1 LAST VALUE 0
J 2
(-6475 1400);
DISPLAY 0.787234 (-6475 1400);
FORCEPROP 1 LAST MATERIAL CHIP
J 0
(-6450 1400);
DISPLAY 0.638298 (-6450 1400);
FORCEPROP 1 LAST TOLERANCE 5%
J 0
(-6550 1275);
DISPLAY 0.638298 (-6550 1275);
FORCEPROP 1 LAST PACK_TYPE 0402LF
J 0
(-6750 1275);
DISPLAY 0.638298 (-6750 1275);
FORCEPROP 1 LAST WATTAGE 1/16W
J 2
(-6550 1225);
DISPLAY 0.638298 (-6550 1225);
FORCEPROP 2 LAST CDS_LIB pure_quanta
J 0
(-6625 1400);
DISPLAY INVISIBLE (-6625 1400);
FORCEPROP 1 LAST PATH I6
J 0
(-6675 1550);
DISPLAY 0.978723 (-6675 1550);
PAINT WHITE (-6675 1550);
DISPLAY INVISIBLE (-6675 1550);
FORCEPROP 1 LAST PART_NUMBER CS00002JB13
J 0
(-6775 1325);
DISPLAY 0.638298 (-6775 1325);
DISPLAY INVISIBLE (-6775 1325);
FORCEADD UNIVERSAL_POWER..1
(-1325 2775);
FORCEPROP 3 LASTPIN (-1325 2725) SIG_NAME P3V3_AUX\g
J 0
(-1315 2735);
DISPLAY 0.659574 (-1315 2735);
PAINT MONO (-1315 2735);
DISPLAY INVISIBLE (-1315 2735);
FORCEPROP 1 LAST HDL_POWER P3V3_AUX
J 1
(-1325 2825);
DISPLAY 0.872340 (-1325 2825);
PAINT GREEN (-1325 2825);
FORCEPROP 2 LAST CDS_LIB pure_quanta_power
J 0
(-1325 2775);
DISPLAY INVISIBLE (-1325 2775);
FORCEPROP 1 LAST PATH I60
J 0
(-1275 2800);
DISPLAY 0.872340 (-1275 2800);
PAINT AQUA (-1275 2800);
DISPLAY INVISIBLE (-1275 2800);
FORCEADD OFFPAGE..2
(-1650 3950);
FORCEPROP 2 LAST $XR0 150 
J 0
(-1461 3950);
DISPLAY 0.638298 (-1461 3950);
PAINT MONO (-1461 3950);
FORCEPROP 2 LAST CDS_LIB standard
J 0
(-1650 3950);
DISPLAY INVISIBLE (-1650 3950);
FORCEPROP 1 LAST OFFPAGE TRUE
J 0
(-1325 3825);
DISPLAY 0.872340 (-1325 3825);
DISPLAY INVISIBLE (-1325 3825);
FORCEPROP 1 LAST COMMENT_BODY TRUE
J 0
(-1695 3855);
DISPLAY 0.872340 (-1695 3855);
PAINT GREEN (-1695 3855);
DISPLAY INVISIBLE (-1695 3855);
FORCEPROP 2 LAST PATH I61
J 0
(-1475 4025);
DISPLAY 0.680851 (-1475 4025);
DISPLAY INVISIBLE (-1475 4025);
FORCEADD OFFPAGE..2
(-1650 3900);
FORCEPROP 2 LAST $XR0 150 
J 0
(-1461 3900);
DISPLAY 0.638298 (-1461 3900);
PAINT MONO (-1461 3900);
FORCEPROP 2 LAST CDS_LIB standard
J 0
(-1650 3900);
DISPLAY INVISIBLE (-1650 3900);
FORCEPROP 1 LAST OFFPAGE TRUE
J 0
(-1325 3775);
DISPLAY 0.872340 (-1325 3775);
DISPLAY INVISIBLE (-1325 3775);
FORCEPROP 1 LAST COMMENT_BODY TRUE
J 0
(-1695 3805);
DISPLAY 0.872340 (-1695 3805);
PAINT GREEN (-1695 3805);
DISPLAY INVISIBLE (-1695 3805);
FORCEPROP 2 LAST PATH I62
J 0
(-1475 3975);
DISPLAY 0.680851 (-1475 3975);
DISPLAY INVISIBLE (-1475 3975);
FORCEADD OFFPAGE..2
(-1650 3800);
FORCEPROP 2 LAST $XR0 122 
J 0
(-1461 3800);
DISPLAY 0.638298 (-1461 3800);
PAINT MONO (-1461 3800);
FORCEPROP 2 LAST CDS_LIB standard
J 0
(-1650 3800);
DISPLAY INVISIBLE (-1650 3800);
FORCEPROP 1 LAST OFFPAGE TRUE
J 0
(-1325 3675);
DISPLAY 0.872340 (-1325 3675);
DISPLAY INVISIBLE (-1325 3675);
FORCEPROP 1 LAST COMMENT_BODY TRUE
J 0
(-1695 3705);
DISPLAY 0.872340 (-1695 3705);
PAINT GREEN (-1695 3705);
DISPLAY INVISIBLE (-1695 3705);
FORCEPROP 2 LAST PATH I63
J 0
(-1475 3875);
DISPLAY 0.680851 (-1475 3875);
DISPLAY INVISIBLE (-1475 3875);
FORCEADD OFFPAGE..2
(-1650 3750);
FORCEPROP 2 LAST $XR0 122 
J 0
(-1461 3750);
DISPLAY 0.638298 (-1461 3750);
PAINT MONO (-1461 3750);
FORCEPROP 2 LAST CDS_LIB standard
J 0
(-1650 3750);
DISPLAY INVISIBLE (-1650 3750);
FORCEPROP 1 LAST OFFPAGE TRUE
J 0
(-1325 3625);
DISPLAY 0.872340 (-1325 3625);
DISPLAY INVISIBLE (-1325 3625);
FORCEPROP 1 LAST COMMENT_BODY TRUE
J 0
(-1695 3655);
DISPLAY 0.872340 (-1695 3655);
PAINT GREEN (-1695 3655);
DISPLAY INVISIBLE (-1695 3655);
FORCEPROP 2 LAST PATH I64
J 0
(-1475 3825);
DISPLAY 0.680851 (-1475 3825);
DISPLAY INVISIBLE (-1475 3825);
FORCEADD OFFPAGE..2
(-625 2250);
FORCEPROP 2 LAST $XR0 234 
J 0
(-436 2250);
DISPLAY 0.638298 (-436 2250);
PAINT MONO (-436 2250);
FORCEPROP 2 LAST CDS_LIB standard
J 0
(-625 2250);
DISPLAY INVISIBLE (-625 2250);
FORCEPROP 1 LAST OFFPAGE TRUE
J 0
(-300 2125);
DISPLAY 0.872340 (-300 2125);
DISPLAY INVISIBLE (-300 2125);
FORCEPROP 1 LAST COMMENT_BODY TRUE
J 0
(-670 2155);
DISPLAY 0.872340 (-670 2155);
PAINT GREEN (-670 2155);
DISPLAY INVISIBLE (-670 2155);
FORCEPROP 2 LAST PATH I65
J 0
(-425 2300);
DISPLAY 0.680851 (-425 2300);
DISPLAY INVISIBLE (-425 2300);
FORCEADD UNIVERSAL_GND..1
(-3625 4850);
FORCEPROP 3 LASTPIN (-3625 4900) SIG_NAME GND\g
J 0
(-3615 4910);
DISPLAY 0.659574 (-3615 4910);
PAINT MONO (-3615 4910);
DISPLAY INVISIBLE (-3615 4910);
FORCEPROP 2 LAST CDS_LIB pure_quanta_power
J 0
(-3625 4850);
DISPLAY INVISIBLE (-3625 4850);
FORCEPROP 1 LAST HDL_POWER GND
J 1
(-3600 4775);
DISPLAY 0.872340 (-3600 4775);
PAINT GREEN (-3600 4775);
DISPLAY INVISIBLE (-3600 4775);
FORCEPROP 1 LAST PATH I66
J 0
(-3550 4850);
DISPLAY 0.872340 (-3550 4850);
PAINT AQUA (-3550 4850);
DISPLAY INVISIBLE (-3550 4850);
FORCEADD OFFPAGE..1
R 2
(-3050 4350);
FORCEPROP 2 LAST $XR0 234 
J 0
(-2864 4350);
DISPLAY 0.638298 (-2864 4350);
PAINT MONO (-2864 4350);
FORCEPROP 2 LAST CDS_LIB standard
J 2
(-3050 4350);
DISPLAY INVISIBLE (-3050 4350);
FORCEPROP 1 LAST OFFPAGE TRUE
J 2
(-3375 4225);
DISPLAY 1.170213 (-3375 4225);
PAINT GREEN (-3375 4225);
DISPLAY INVISIBLE (-3375 4225);
FORCEPROP 1 LAST COMMENT_BODY TRUE
J 2
(-3175 4250);
DISPLAY 1.170213 (-3175 4250);
PAINT GREEN (-3175 4250);
DISPLAY INVISIBLE (-3175 4250);
FORCEPROP 2 LAST PATH I67
J 0
(-2850 4400);
DISPLAY 0.680851 (-2850 4400);
DISPLAY INVISIBLE (-2850 4400);
FORCEADD Q_CAP..1
(-3950 5175);
FORCEPROP 1 LAST LOCATION C1884
J 0
(-3900 5375);
DISPLAY 0.638298 (-3900 5375);
FORCEPROP 0 LAST $SEC 1
J 0
(-3900 5325);
DISPLAY 0.680851 (-3900 5325);
PAINT MONO (-3900 5325);
DISPLAY INVISIBLE (-3900 5325);
FORCEPROP 0 LAST CDS_SEC 1
J 0
(-3900 5325);
DISPLAY 1.021277 (-3900 5325);
DISPLAY INVISIBLE (-3900 5325);
FORCEPROP 1 LASTPIN (-3950 5275) $PN 1
J 0
(-3940 5255);
DISPLAY 0.787234 (-3940 5255);
PAINT MONO (-3940 5255);
FORCEPROP 1 LASTPIN (-3950 5075) $PN 2
J 0
(-3940 5055);
DISPLAY 0.787234 (-3940 5055);
PAINT MONO (-3940 5055);
FORCEPROP 1 LAST VALUE 1UF
J 0
(-3900 5325);
DISPLAY 0.638298 (-3900 5325);
FORCEPROP 1 LAST PACK_TYPE C0402
J 0
(-3900 5125);
DISPLAY 0.638298 (-3900 5125);
FORCEPROP 1 LAST VOLTAGE 25V
J 0
(-3900 5275);
DISPLAY 0.638298 (-3900 5275);
FORCEPROP 1 LAST TOLERANCE 10%
J 0
(-3900 5225);
DISPLAY 0.638298 (-3900 5225);
FORCEPROP 1 LAST MATERIAL X6S
J 0
(-3900 5175);
DISPLAY 0.638298 (-3900 5175);
FORCEPROP 2 LAST CDS_LIB pure_quanta
J 0
(-3950 5175);
DISPLAY INVISIBLE (-3950 5175);
FORCEPROP 2 LAST BOM_COST VR_SYSTEM 
J 0
(-3900 5325);
DISPLAY 0.680851 (-3900 5325);
DISPLAY INVISIBLE (-3900 5325);
FORCEPROP 1 LAST PATH I68
J 0
(-3900 5325);
DISPLAY 0.978723 (-3900 5325);
PAINT WHITE (-3900 5325);
DISPLAY INVISIBLE (-3900 5325);
FORCEPROP 1 LAST PART_NUMBER CH5104KEB02
J 0
(-3900 5075);
DISPLAY 0.510638 (-3900 5075);
DISPLAY INVISIBLE (-3900 5075);
FORCEADD Q_CAP..1
(-3625 5175);
FORCEPROP 1 LAST LOCATION C97
J 0
(-3575 5275);
DISPLAY 0.787234 (-3575 5275);
FORCEPROP 0 LAST $SEC 1
J 0
(-3575 5325);
DISPLAY 0.680851 (-3575 5325);
PAINT MONO (-3575 5325);
DISPLAY INVISIBLE (-3575 5325);
FORCEPROP 0 LAST CDS_SEC 1
J 0
(-3575 5325);
DISPLAY 1.021277 (-3575 5325);
DISPLAY INVISIBLE (-3575 5325);
FORCEPROP 1 LASTPIN (-3625 5275) $PN 1
J 0
(-3615 5255);
DISPLAY 0.787234 (-3615 5255);
PAINT MONO (-3615 5255);
FORCEPROP 1 LASTPIN (-3625 5075) $PN 2
J 0
(-3615 5055);
DISPLAY 0.787234 (-3615 5055);
PAINT MONO (-3615 5055);
FORCEPROP 1 LAST PACK_TYPE 0402
J 0
(-3575 5025);
DISPLAY 0.638298 (-3575 5025);
FORCEPROP 1 LAST VALUE 0.1UF
J 0
(-3575 5225);
DISPLAY 0.638298 (-3575 5225);
FORCEPROP 1 LAST MATERIAL X7R
J 0
(-3575 5075);
DISPLAY 0.638298 (-3575 5075);
FORCEPROP 1 LAST VOLTAGE 25V
J 0
(-3575 5175);
DISPLAY 0.638298 (-3575 5175);
FORCEPROP 1 LAST TOLERANCE 10%
J 0
(-3575 5125);
DISPLAY 0.638298 (-3575 5125);
FORCEPROP 2 LAST CDS_LIB pure_quanta
J 0
(-3625 5175);
DISPLAY INVISIBLE (-3625 5175);
FORCEPROP 1 LAST PATH I69
J 0
(-3575 5325);
DISPLAY 0.978723 (-3575 5325);
PAINT WHITE (-3575 5325);
DISPLAY INVISIBLE (-3575 5325);
FORCEPROP 1 LAST PART_NUMBER CH4104K1B00
J 0
(-3575 5025);
DISPLAY 0.808511 (-3575 5025);
DISPLAY INVISIBLE (-3575 5025);
FORCEADD Q_RES..1
(-6625 1500);
FORCEPROP 1 LAST LOCATION R3326
J 0
(-6850 1500);
DISPLAY 0.638298 (-6850 1500);
FORCEPROP 0 LAST $SEC 1
J 0
(-6450 1550);
DISPLAY 0.680851 (-6450 1550);
PAINT MONO (-6450 1550);
DISPLAY INVISIBLE (-6450 1550);
FORCEPROP 0 LAST CDS_SEC 1
J 0
(-6450 1550);
DISPLAY 1.021277 (-6450 1550);
DISPLAY INVISIBLE (-6450 1550);
FORCEPROP 1 LASTPIN (-6725 1500) $PN 1
J 0
(-6713 1512);
DISPLAY 0.787234 (-6713 1512);
PAINT MONO (-6713 1512);
FORCEPROP 1 LASTPIN (-6525 1500) $PN 2
J 0
(-6563 1512);
DISPLAY 0.787234 (-6563 1512);
PAINT MONO (-6563 1512);
FORCEPROP 1 LAST MATERIAL CHIP
J 0
(-6450 1500);
DISPLAY 0.638298 (-6450 1500);
FORCEPROP 1 LAST VALUE 0
J 2
(-6475 1500);
DISPLAY 0.787234 (-6475 1500);
FORCEPROP 1 LAST WATTAGE 1/16W
J 2
(-6150 1600);
DISPLAY 0.638298 (-6150 1600);
DISPLAY INVISIBLE (-6150 1600);
FORCEPROP 1 LAST TOLERANCE 5%
J 0
(-6325 1500);
DISPLAY 0.638298 (-6325 1500);
DISPLAY INVISIBLE (-6325 1500);
FORCEPROP 1 LAST PACK_TYPE 0402LF
J 0
(-6225 1500);
DISPLAY 0.638298 (-6225 1500);
DISPLAY INVISIBLE (-6225 1500);
FORCEPROP 2 LAST CDS_LIB pure_quanta
J 0
(-6625 1500);
DISPLAY INVISIBLE (-6625 1500);
FORCEPROP 1 LAST PATH I7
J 0
(-6675 1650);
DISPLAY 0.978723 (-6675 1650);
PAINT WHITE (-6675 1650);
DISPLAY INVISIBLE (-6675 1650);
FORCEPROP 1 LAST PART_NUMBER CS00002JB13
J 0
(-6500 1550);
DISPLAY 0.638298 (-6500 1550);
DISPLAY INVISIBLE (-6500 1550);
FORCEADD UNIVERSAL_POWER..1
(-3625 5500);
FORCEPROP 3 LASTPIN (-3625 5450) SIG_NAME VFG_3P3A_CLK_GEN\g
J 0
(-3615 5460);
DISPLAY 0.659574 (-3615 5460);
PAINT MONO (-3615 5460);
DISPLAY INVISIBLE (-3615 5460);
FORCEPROP 1 LAST HDL_POWER VFG_3P3A_CLK_GEN
J 1
(-3625 5550);
DISPLAY 0.872340 (-3625 5550);
PAINT GREEN (-3625 5550);
FORCEPROP 2 LAST CDS_LIB pure_quanta_power
J 0
(-3625 5500);
DISPLAY INVISIBLE (-3625 5500);
FORCEPROP 1 LAST PATH I70
J 0
(-3575 5525);
DISPLAY 0.872340 (-3575 5525);
PAINT AQUA (-3575 5525);
DISPLAY INVISIBLE (-3575 5525);
FORCEADD UNIVERSAL_GND..1
(-3600 2700);
FORCEPROP 3 LASTPIN (-3600 2750) SIG_NAME GND\g
J 0
(-3590 2760);
DISPLAY 0.659574 (-3590 2760);
PAINT MONO (-3590 2760);
DISPLAY INVISIBLE (-3590 2760);
FORCEPROP 2 LAST CDS_LIB pure_quanta_power
J 0
(-3600 2700);
DISPLAY INVISIBLE (-3600 2700);
FORCEPROP 1 LAST HDL_POWER GND
J 1
(-3575 2625);
DISPLAY 0.872340 (-3575 2625);
PAINT GREEN (-3575 2625);
DISPLAY INVISIBLE (-3575 2625);
FORCEPROP 1 LAST PATH I71
J 0
(-3525 2700);
DISPLAY 0.872340 (-3525 2700);
PAINT AQUA (-3525 2700);
DISPLAY INVISIBLE (-3525 2700);
FORCEADD Q_RES..2
(-7975 3925);
FORCEPROP 1 LAST LOCATION R4521
J 0
(-7930 4050);
DISPLAY 0.978723 (-7930 4050);
FORCEPROP 0 LAST $SEC 1
J 0
(-7925 4100);
DISPLAY 0.680851 (-7925 4100);
PAINT MONO (-7925 4100);
DISPLAY INVISIBLE (-7925 4100);
FORCEPROP 0 LAST CDS_SEC 1
J 0
(-7925 4100);
DISPLAY 0.680851 (-7925 4100);
DISPLAY INVISIBLE (-7925 4100);
FORCEPROP 1 LASTPIN (-7975 4025) $PN 1
J 0
(-7970 3987);
DISPLAY 0.787234 (-7970 3987);
PAINT MONO (-7970 3987);
FORCEPROP 1 LASTPIN (-7975 3825) $PN 2
J 0
(-7970 3835);
DISPLAY 0.787234 (-7970 3835);
PAINT MONO (-7970 3835);
FORCEPROP 1 LAST PACK_TYPE 0402LF
J 0
(-7925 3800);
DISPLAY 0.510638 (-7925 3800);
FORCEPROP 1 LAST TOLERANCE 1%
J 0
(-7930 3950);
DISPLAY 0.510638 (-7930 3950);
FORCEPROP 1 LAST WATTAGE 1/16W
J 0
(-7935 3900);
DISPLAY 0.510638 (-7935 3900);
FORCEPROP 1 LAST MATERIAL CHIP
J 0
(-7935 3850);
DISPLAY 0.510638 (-7935 3850);
FORCEPROP 1 LAST VALUE 1K
J 0
(-7930 4000);
DISPLAY 0.510638 (-7930 4000);
FORCEPROP 2 LAST CDS_LIB pure_quanta
J 0
(-7975 3925);
DISPLAY INVISIBLE (-7975 3925);
FORCEPROP 1 LAST PATH I73
J 0
(-7925 4100);
DISPLAY 0.978723 (-7925 4100);
PAINT WHITE (-7925 4100);
DISPLAY INVISIBLE (-7925 4100);
FORCEPROP 1 LAST PART_NUMBER CS21002FB06
J 0
(-7935 3800);
DISPLAY 0.510638 (-7935 3800);
DISPLAY INVISIBLE (-7935 3800);
FORCEADD Q_RES..2
(-6325 1800);
FORCEPROP 1 LAST LOCATION R3322
J 0
(-6275 1925);
DISPLAY 0.787234 (-6275 1925);
FORCEPROP 0 LAST $SEC 1
J 0
(-6275 1975);
DISPLAY 0.680851 (-6275 1975);
PAINT MONO (-6275 1975);
DISPLAY INVISIBLE (-6275 1975);
FORCEPROP 0 LAST CDS_SEC 1
J 0
(-6275 1975);
DISPLAY 0.680851 (-6275 1975);
DISPLAY INVISIBLE (-6275 1975);
FORCEPROP 1 LASTPIN (-6325 1900) $PN 1
J 0
(-6320 1862);
DISPLAY 0.787234 (-6320 1862);
PAINT MONO (-6320 1862);
FORCEPROP 1 LASTPIN (-6325 1700) $PN 2
J 0
(-6320 1710);
DISPLAY 0.787234 (-6320 1710);
PAINT MONO (-6320 1710);
FORCEPROP 1 LAST TOLERANCE 1%
J 0
(-6280 1825);
DISPLAY 0.787234 (-6280 1825);
FORCEPROP 1 LAST PACK_TYPE 0402LF
J 0
(-6285 1625);
DISPLAY 0.787234 (-6285 1625);
FORCEPROP 1 LAST WATTAGE 1/16W
J 0
(-6285 1775);
DISPLAY 0.787234 (-6285 1775);
FORCEPROP 1 LAST MATERIAL CHIP
J 0
(-6285 1725);
DISPLAY 0.787234 (-6285 1725);
FORCEPROP 1 LAST VALUE 1K
J 0
(-6280 1875);
DISPLAY 0.787234 (-6280 1875);
FORCEPROP 2 LAST CDS_LIB pure_quanta
J 0
(-6325 1800);
DISPLAY INVISIBLE (-6325 1800);
FORCEPROP 1 LAST PATH I74
J 0
(-6275 1975);
DISPLAY 0.978723 (-6275 1975);
PAINT WHITE (-6275 1975);
DISPLAY INVISIBLE (-6275 1975);
FORCEPROP 1 LAST PART_NUMBER CS21002FB06
J 0
(-6285 1675);
DISPLAY 0.787234 (-6285 1675);
DISPLAY INVISIBLE (-6285 1675);
FORCEADD Q_CAP..1
R 2
(-7250 3900);
FORCEPROP 1 LAST LOCATION C71
J 2
(-7300 4000);
DISPLAY 0.638298 (-7300 4000);
FORCEPROP 0 LAST $SEC 1
J 0
(-7300 4050);
DISPLAY 0.680851 (-7300 4050);
PAINT MONO (-7300 4050);
DISPLAY INVISIBLE (-7300 4050);
FORCEPROP 0 LAST CDS_SEC 1
J 0
(-7300 4050);
DISPLAY 0.680851 (-7300 4050);
DISPLAY INVISIBLE (-7300 4050);
FORCEPROP 1 LASTPIN (-7250 4000) $PN 1
J 2
(-7260 3980);
DISPLAY 0.787234 (-7260 3980);
PAINT MONO (-7260 3980);
FORCEPROP 1 LASTPIN (-7250 3800) $PN 2
J 2
(-7260 3780);
DISPLAY 0.787234 (-7260 3780);
PAINT MONO (-7260 3780);
FORCEPROP 1 LAST VALUE 4.7PF
J 2
(-7300 3950);
DISPLAY 0.638298 (-7300 3950);
FORCEPROP 1 LAST VOLTAGE 50V
J 2
(-7300 3900);
DISPLAY 0.638298 (-7300 3900);
FORCEPROP 1 LAST PACK_TYPE C0402
J 2
(-7300 3700);
DISPLAY 0.638298 (-7300 3700);
FORCEPROP 1 LAST MATERIAL NPO
J 2
(-7300 3800);
DISPLAY 0.638298 (-7300 3800);
FORCEPROP 1 LAST TOLERANCE 0.1P
J 2
(-7300 3850);
DISPLAY 0.638298 (-7300 3850);
FORCEPROP 2 LAST CDS_LIB pure_quanta
J 2
(-7250 3900);
DISPLAY INVISIBLE (-7250 3900);
FORCEPROP 1 LAST PATH I75
J 2
(-7300 4050);
DISPLAY 0.978723 (-7300 4050);
PAINT WHITE (-7300 4050);
DISPLAY INVISIBLE (-7300 4050);
FORCEPROP 1 LAST PART_NUMBER CH-4716TB06
J 2
(-7300 3750);
DISPLAY 0.638298 (-7300 3750);
DISPLAY INVISIBLE (-7300 3750);
FORCEADD Q_CAP..1
(-6375 3900);
FORCEPROP 1 LAST LOCATION C94
J 0
(-6325 4000);
DISPLAY 0.510638 (-6325 4000);
FORCEPROP 0 LAST $SEC 1
J 0
(-6325 4025);
DISPLAY 0.680851 (-6325 4025);
PAINT MONO (-6325 4025);
DISPLAY INVISIBLE (-6325 4025);
FORCEPROP 0 LAST CDS_SEC 1
J 0
(-6325 4025);
DISPLAY 0.680851 (-6325 4025);
DISPLAY INVISIBLE (-6325 4025);
FORCEPROP 1 LASTPIN (-6375 4000) $PN 1
J 0
(-6365 3980);
DISPLAY 0.787234 (-6365 3980);
PAINT MONO (-6365 3980);
FORCEPROP 1 LASTPIN (-6375 3800) $PN 2
J 0
(-6365 3780);
DISPLAY 0.787234 (-6365 3780);
PAINT MONO (-6365 3780);
FORCEPROP 1 LAST PACK_TYPE C0402
J 0
(-6325 3700);
DISPLAY 0.404255 (-6325 3700);
FORCEPROP 1 LAST VALUE 4.7PF
J 0
(-6325 3950);
DISPLAY 0.404255 (-6325 3950);
FORCEPROP 1 LAST MATERIAL NPO
J 0
(-6325 3800);
DISPLAY 0.404255 (-6325 3800);
FORCEPROP 1 LAST TOLERANCE 0.1P
J 0
(-6325 3850);
DISPLAY 0.404255 (-6325 3850);
FORCEPROP 1 LAST VOLTAGE 50V
J 0
(-6325 3900);
DISPLAY 0.404255 (-6325 3900);
FORCEPROP 2 LAST CDS_LIB pure_quanta
J 0
(-6375 3900);
DISPLAY INVISIBLE (-6375 3900);
FORCEPROP 1 LAST PATH I76
J 0
(-6325 4050);
DISPLAY 0.978723 (-6325 4050);
PAINT WHITE (-6325 4050);
DISPLAY INVISIBLE (-6325 4050);
FORCEPROP 1 LAST PART_NUMBER CH-4716TB06
J 0
(-6325 3750);
DISPLAY 0.404255 (-6325 3750);
DISPLAY INVISIBLE (-6325 3750);
FORCEADD 9FGL0251DKILFT..1
(-4300 3700);
FORCEPROP 1 LAST LOCATION U247
J 0
(-4700 4550);
DISPLAY 0.723404 (-4700 4550);
PAINT GREEN (-4700 4550);
FORCEPROP 2 LAST SEC 1
J 0
(-4675 4825);
DISPLAY 0.680851 (-4675 4825);
PAINT MONO (-4675 4825);
DISPLAY INVISIBLE (-4675 4825);
FORCEPROP 2 LASTPIN (-4850 3250) $PN 22
J 2
(-4860 3260);
DISPLAY 0.680851 (-4860 3260);
PAINT MONO (-4860 3260);
FORCEPROP 2 LASTPIN (-4850 3150) $PN 23
J 2
(-4860 3160);
DISPLAY 0.680851 (-4860 3160);
PAINT MONO (-4860 3160);
FORCEPROP 2 LASTPIN (-3750 3950) $PN 13
J 0
(-3740 3960);
DISPLAY 0.680851 (-3740 3960);
PAINT MONO (-3740 3960);
FORCEPROP 2 LASTPIN (-3750 3900) $PN 14
J 0
(-3740 3910);
DISPLAY 0.680851 (-3740 3910);
PAINT MONO (-3740 3910);
FORCEPROP 2 LASTPIN (-3750 3800) $PN 17
J 0
(-3740 3810);
DISPLAY 0.680851 (-3740 3810);
PAINT MONO (-3740 3810);
FORCEPROP 2 LASTPIN (-3750 3750) $PN 18
J 0
(-3740 3760);
DISPLAY 0.680851 (-3740 3760);
PAINT MONO (-3740 3760);
FORCEPROP 2 LASTPIN (-3750 3250) $PN 10
J 0
(-3740 3260);
DISPLAY 0.680851 (-3740 3260);
PAINT MONO (-3740 3260);
FORCEPROP 2 LASTPIN (-3750 3200) $PN 21
J 0
(-3740 3210);
DISPLAY 0.680851 (-3740 3210);
PAINT MONO (-3740 3210);
FORCEPROP 2 LASTPIN (-3750 3300) $PN 15
J 0
(-3740 3310);
DISPLAY 0.680851 (-3740 3310);
PAINT MONO (-3740 3310);
FORCEPROP 2 LASTPIN (-3750 3350) $PN 6
J 0
(-3740 3360);
DISPLAY 0.680851 (-3740 3360);
PAINT MONO (-3740 3360);
FORCEPROP 2 LASTPIN (-3750 3400) $PN 5
J 0
(-3740 3410);
DISPLAY 0.680851 (-3740 3410);
PAINT MONO (-3740 3410);
FORCEPROP 2 LASTPIN (-3750 3450) $PN 24
J 0
(-3740 3460);
DISPLAY 0.680851 (-3740 3460);
PAINT MONO (-3740 3460);
FORCEPROP 2 LASTPIN (-4850 3700) $PN 8
J 2
(-4860 3710);
DISPLAY 0.680851 (-4860 3710);
PAINT MONO (-4860 3710);
FORCEPROP 2 LASTPIN (-4850 3650) $PN 9
J 2
(-4860 3660);
DISPLAY 0.680851 (-4860 3660);
PAINT MONO (-4860 3660);
FORCEPROP 2 LASTPIN (-3750 3050) $PN 25
J 0
(-3740 3060);
DISPLAY 0.680851 (-3740 3060);
PAINT MONO (-3740 3060);
FORCEPROP 2 LASTPIN (-4850 4200) $PN 11
J 2
(-4860 4210);
DISPLAY 0.680851 (-4860 4210);
PAINT MONO (-4860 4210);
FORCEPROP 2 LASTPIN (-4850 4250) $PN 20
J 2
(-4860 4260);
DISPLAY 0.680851 (-4860 4260);
PAINT MONO (-4860 4260);
FORCEPROP 2 LASTPIN (-4850 4350) $PN 16
J 2
(-4860 4360);
DISPLAY 0.680851 (-4860 4360);
PAINT MONO (-4860 4360);
FORCEPROP 2 LASTPIN (-4850 4300) $PN 7
J 2
(-4860 4310);
DISPLAY 0.680851 (-4860 4310);
PAINT MONO (-4860 4310);
FORCEPROP 2 LASTPIN (-4850 4150) $PN 3
J 2
(-4860 4160);
DISPLAY 0.680851 (-4860 4160);
PAINT MONO (-4860 4160);
FORCEPROP 2 LASTPIN (-4850 3550) $PN 12
J 2
(-4860 3560);
DISPLAY 0.680851 (-4860 3560);
PAINT MONO (-4860 3560);
FORCEPROP 2 LASTPIN (-4850 3500) $PN 19
J 2
(-4860 3510);
DISPLAY 0.680851 (-4860 3510);
PAINT MONO (-4860 3510);
FORCEPROP 2 LASTPIN (-3750 4350) $PN 4
J 0
(-3740 4360);
DISPLAY 0.680851 (-3740 4360);
PAINT MONO (-3740 4360);
FORCEPROP 2 LASTPIN (-4850 3900) $PN 2
J 2
(-4860 3910);
DISPLAY 0.680851 (-4860 3910);
PAINT MONO (-4860 3910);
FORCEPROP 2 LASTPIN (-4850 3950) $PN 1
J 2
(-4860 3960);
DISPLAY 0.680851 (-4860 3960);
PAINT MONO (-4860 3960);
FORCEPROP 2 LAST PART_TYPE SMLF
J 0
(-4678 4634);
DISPLAY 0.680851 (-4678 4634);
FORCEPROP 1 LAST MATERIAL IC
J 0
(-4697 4417);
DISPLAY 0.723404 (-4697 4417);
PAINT GREEN (-4697 4417);
FORCEPROP 2 LAST VALUE 9FGL0251DKILFT
J 0
(-4678 4584);
DISPLAY 0.680851 (-4678 4584);
FORCEPROP 1 LAST CDS_LMAN_SYM_OUTLINE -400,700,400,-700
J 0
(-4300 3700);
DISPLAY 0.468085 (-4300 3700);
PAINT GREEN (-4300 3700);
DISPLAY INVISIBLE (-4300 3700);
FORCEPROP 1 LAST NEEDS_NO_SIZE TRUE
J 0
(-4300 3700);
DISPLAY 0.723404 (-4300 3700);
PAINT GREEN (-4300 3700);
DISPLAY INVISIBLE (-4300 3700);
FORCEPROP 2 LAST CDS_LIB pure_quanta
J 0
(-4300 3700);
DISPLAY INVISIBLE (-4300 3700);
FORCEPROP 2 LAST SEC_TYPE 
J 0
(-4675 4825);
DISPLAY 0.680851 (-4675 4825);
DISPLAY INVISIBLE (-4675 4825);
FORCEPROP 1 LAST PATH I77
J 0
(-4300 3700);
DISPLAY 0.723404 (-4300 3700);
PAINT GREEN (-4300 3700);
DISPLAY INVISIBLE (-4300 3700);
FORCEPROP 1 LAST PART_NUMBER AL000251002
J 0
(-4700 4475);
DISPLAY 0.723404 (-4700 4475);
PAINT GREEN (-4700 4475);
DISPLAY INVISIBLE (-4700 4475);
FORCEADD Q_RES..2
(-6300 1175);
FORCEPROP 1 LAST LOCATION R4514
J 0
(-6250 1300);
DISPLAY 0.978723 (-6250 1300);
FORCEPROP 0 LAST $SEC 1
J 0
(-6250 1350);
DISPLAY 0.680851 (-6250 1350);
PAINT MONO (-6250 1350);
DISPLAY INVISIBLE (-6250 1350);
FORCEPROP 0 LAST CDS_SEC 1
J 0
(-6250 1350);
DISPLAY 1.021277 (-6250 1350);
DISPLAY INVISIBLE (-6250 1350);
FORCEPROP 1 LASTPIN (-6300 1275) $PN 1
J 0
(-6295 1237);
DISPLAY 0.787234 (-6295 1237);
PAINT MONO (-6295 1237);
FORCEPROP 1 LASTPIN (-6300 1075) $PN 2
J 0
(-6295 1085);
DISPLAY 0.787234 (-6295 1085);
PAINT MONO (-6295 1085);
FORCEPROP 1 LAST TOLERANCE 1%
J 0
(-6250 1200);
DISPLAY 0.787234 (-6250 1200);
FORCEPROP 1 LAST VALUE 4.7K
J 0
(-6250 1250);
DISPLAY 0.787234 (-6250 1250);
FORCEPROP 1 LAST WATTAGE 1/16W
J 0
(-6250 1125);
DISPLAY 0.787234 (-6250 1125);
FORCEPROP 1 LAST MATERIAL EMPTY
J 0
(-6250 1075);
DISPLAY 0.787234 (-6250 1075);
PAINT RED (-6250 1075);
FORCEPROP 1 LAST PACK_TYPE 0402LF
J 0
(-6250 975);
DISPLAY 0.787234 (-6250 975);
FORCEPROP 2 LAST CDS_LIB pure_quanta
J 0
(-6300 1175);
DISPLAY INVISIBLE (-6300 1175);
FORCEPROP 1 LAST PATH I8
J 0
(-6250 1350);
DISPLAY 0.978723 (-6250 1350);
PAINT WHITE (-6250 1350);
DISPLAY INVISIBLE (-6250 1350);
FORCEPROP 1 LAST PART_NUMBER CS24702FB06
J 0
(-6250 1025);
DISPLAY 0.787234 (-6250 1025);
DISPLAY INVISIBLE (-6250 1025);
FORCEADD DESIGN_NOTE..1
(-5375 5925);
FORCEPROP 0 LAST S1 PLACE CLOSE TO U247 ALL VDD PINS
J 0
(-5525 5775);
DISPLAY 1.021277 (-5525 5775);
PAINT SKYBLUE (-5525 5775);
FORCEPROP 2 LAST CDS_LIB pure_quanta_power
J 0
(-5375 5925);
DISPLAY INVISIBLE (-5375 5925);
FORCEPROP 1 LAST COMMENT_BODY TRUE
J 0
(-5350 6025);
DISPLAY 0.978723 (-5350 6025);
DISPLAY INVISIBLE (-5350 6025);
FORCEADD DNS..2
(-6300 1150);
PAINT RED (-6300 1150);
FORCEPROP 2 LAST CDS_LIB mstr_misc
J 0
(-6300 1150);
DISPLAY INVISIBLE (-6300 1150);
FORCEPROP 1 LAST COMMENT_BODY TRUE
J 0
(-6300 1150);
DISPLAY INVISIBLE (-6300 1150);
FORCEADD DNS..2
(-1325 1200);
PAINT RED (-1325 1200);
FORCEPROP 2 LAST CDS_LIB mstr_misc
J 0
(-1325 1200);
DISPLAY INVISIBLE (-1325 1200);
FORCEPROP 1 LAST COMMENT_BODY TRUE
J 0
(-1325 1200);
DISPLAY INVISIBLE (-1325 1200);
FORCEADD DNS..2
(-2650 1650);
PAINT RED (-2650 1650);
FORCEPROP 2 LAST CDS_LIB mstr_misc
J 0
(-2650 1650);
DISPLAY INVISIBLE (-2650 1650);
FORCEPROP 1 LAST COMMENT_BODY TRUE
J 0
(-2650 1650);
DISPLAY INVISIBLE (-2650 1650);
FORCEADD QUANTA_TITLE_BLOCK_C..1
(0 0);
FORCEPROP 0 LAST CDS_CON_LAST_MODIFIED Thu Sep 14 16:12:33 2023
J 0
(-1885 15);
DISPLAY INVISIBLE (-1885 15);
FORCEPROP 1 LAST CUSTOM_TXT_CDS <CON_LAST_MODIFIED>
J 0
(-1885 15);
DISPLAY 0.978723 (-1885 15);
FORCEPROP 2 LAST CUSTOM_TXT_CDS <XR_PAGE_TITLE>
J 0
(-7890 5250);
DISPLAY 0.638298 (-7890 5250);
PAINT PINK (-7890 5250);
DISPLAY INVISIBLE (-7890 5250);
FORCEPROP 1 LAST CUSTOM_TXT_CDS <NAME_2>
J 0
(-3175 50);
FORCEPROP 1 LAST CUSTOM_TXT_CDS <NAME_1>
J 0
(-3175 175);
FORCEPROP 1 LAST CUSTOM_TXT_CDS <Q_NUMBER>
J 0
(-1403 103);
DISPLAY 1.212766 (-1403 103);
FORCEPROP 1 LAST CUSTOM_TXT_CDS <Q_PROJ>
J 0
(-2382 102);
DISPLAY 1.212766 (-2382 102);
FORCEPROP 1 LAST CUSTOM_TXT_CDS <Q_REV>
J 0
(-184 103);
DISPLAY 1.212766 (-184 103);
FORCEPROP 1 LAST CUSTOM_TXT_CDS <CON_PAGE_NUM> OF <CON_TOTAL_PAGES>
J 0
(-446 18);
DISPLAY 0.978723 (-446 18);
FORCEPROP 1 LAST Q_TITLE CLK-GEN(NON SSC)
J 0
(-9366 26);
DISPLAY 2.446809 (-9366 26);
PAINT GREEN (-9366 26);
FORCEPROP 2 LAST PAGE_BORDER TRUE
J 0
(-7890 5250);
DISPLAY 0.638298 (-7890 5250);
PAINT PINK (-7890 5250);
DISPLAY INVISIBLE (-7890 5250);
FORCEPROP 2 LAST CDS_LIB pure_quanta
J 0
(0 0);
DISPLAY INVISIBLE (0 0);
FORCEPROP 1 LAST CDS_LMAN_SYM_OUTLINE -9475,6775,100,-125
J 0
(0 0);
DISPLAY 0.468085 (0 0);
PAINT GREEN (0 0);
DISPLAY INVISIBLE (0 0);
FORCEPROP 2 LAST CDS_XR_PAGE_TITLE CR-234 : @T6G_MB_LIB.T6G(SCH_1):PAGE234
J 0
(-7890 5250);
DISPLAY 0.638298 (-7890 5250);
PAINT PINK (-7890 5250);
DISPLAY INVISIBLE (-7890 5250);
FORCEPROP 1 LAST Q_DEPT BU9
J 1
(-3763 49);
DISPLAY 1.957447 (-3763 49);
PAINT GREEN (-3763 49);
DISPLAY INVISIBLE (-3763 49);
FORCEPROP 1 LAST COMMENT_BODY TRUE
J 0
(12 -13);
DISPLAY 0.978723 (12 -13);
PAINT GREEN (12 -13);
DISPLAY INVISIBLE (12 -13);
WIRE 16 -1 (-7250 3800)(-7250 3750);
WIRE 16 -1 (-7075 3900)(-7125 3900);
WIRE 16 -1 (-7125 3900)(-7125 3850);
WIRE 16 -1 (-6325 1900)(-6325 2025);
WIRE 16 -1 (-6375 3800)(-6375 3725);
WIRE 16 -1 (-6525 3900)(-6475 3900);
WIRE 16 -1 (-6475 3900)(-6475 3850);
WIRE 16 -1 (-5325 1350)(-5450 1350);
WIRE 16 -1 (-5450 1350)(-5450 1225);
WIRE 16 -1 (-5275 1925)(-5275 2025);
WIRE 16 -1 (-7975 4025)(-7975 4150);
WIRE 16 -1 (-4850 4350)(-5400 4350);
WIRE 16 -1 (-5400 4350)(-5400 4525);
WIRE 16 -1 (-2650 1100)(-2650 975);
WIRE 16 -1 (-2650 1775)(-2650 1900);
WIRE 16 -1 (-6300 1075)(-6300 775);
WIRE 16 -1 (-1325 1125)(-1325 1000);
WIRE 16 -1 (-1325 1800)(-1325 1925);
WIRE 16 -1 (-1325 2600)(-1325 2725);
WIRE 16 -1 (-6725 1400)(-7625 1400);
FORCEPROP 2 LAST SIG_NAME CLK_GEN2_GPU_FPGA_OE_N
J 0
(-7560 1410);
DISPLAY 0.680851 (-7560 1410);
PAINT WHITE (-7560 1410);
WIRE 16 -1 (-6725 1500)(-7625 1500);
FORCEPROP 2 LAST SIG_NAME GPU_FPGA_READY_N
J 0
(-7560 1510);
DISPLAY 0.680851 (-7560 1510);
PAINT WHITE (-7560 1510);
WIRE 16 -1 (-3600 3050)(-3600 3200);
WIRE 16 -1 (-3750 3050)(-3600 3050);
WIRE 16 -1 (-3600 2750)(-3600 3050);
WIRE 16 -1 (-3600 3250)(-3600 3200);
WIRE 16 -1 (-3750 3200)(-3600 3200);
WIRE 16 -1 (-3600 3300)(-3600 3250);
WIRE 16 -1 (-3750 3250)(-3600 3250);
WIRE 16 -1 (-3600 3350)(-3600 3300);
WIRE 16 -1 (-3750 3300)(-3600 3300);
WIRE 16 -1 (-3600 3400)(-3600 3350);
WIRE 16 -1 (-3750 3350)(-3600 3350);
WIRE 16 -1 (-3600 3450)(-3600 3400);
WIRE 16 -1 (-3750 3400)(-3600 3400);
WIRE 16 -1 (-3750 3450)(-3600 3450);
WIRE 16 -1 (-6275 4575)(-6125 4575);
WIRE 16 -1 (-6125 4575)(-6125 3950);
WIRE 16 -1 (-6125 3950)(-4850 3950);
FORCEPROP 2 LAST SIG_NAME CLK_GEN2_XTAL_IN
J 0
(-5860 3960);
DISPLAY 0.638298 (-5860 3960);
PAINT WHITE (-5860 3960);
FORCEPROP 2 LASTPROP $XRERR UNIQUE?
J 0
(-6100 3960);
DISPLAY 0.638298 (-6100 3960);
PAINT MONO (-6100 3960);
DISPLAY INVISIBLE (-6100 3960);
WIRE 16 -1 (-6200 4100)(-6375 4100);
WIRE 16 -1 (-6200 4100)(-6200 3900);
WIRE 16 -1 (-6525 4100)(-6375 4100);
WIRE 16 -1 (-6375 4000)(-6375 4100);
WIRE 16 -1 (-6200 3900)(-4850 3900);
FORCEPROP 2 LAST SIG_NAME CLK_GEN2_XTAL_OUT
J 0
(-5860 3910);
DISPLAY 0.638298 (-5860 3910);
PAINT WHITE (-5860 3910);
FORCEPROP 2 LASTPROP $XRERR UNIQUE?
J 0
(-6100 3910);
DISPLAY 0.638298 (-6100 3910);
PAINT MONO (-6100 3910);
DISPLAY INVISIBLE (-6100 3910);
WIRE 16 -1 (-3950 5075)(-3950 4975);
WIRE 16 -1 (-3950 4975)(-3625 4975);
WIRE 16 -1 (-3625 5075)(-3625 4975);
WIRE 16 -1 (-3625 4975)(-3625 4900);
WIRE 16 -1 (-4750 5100)(-4750 4975);
WIRE 16 -1 (-4500 4975)(-4750 4975);
WIRE 16 -1 (-4975 4975)(-4750 4975);
WIRE 16 -1 (-4975 5100)(-4975 4975);
WIRE 16 -1 (-5300 4975)(-4975 4975);
WIRE 16 -1 (-4500 5100)(-4500 4975);
WIRE 16 -1 (-4500 4975)(-4500 4900);
WIRE 16 -1 (-5300 5100)(-5300 4975);
WIRE 16 -1 (-5300 4975)(-5700 4975);
WIRE 16 -1 (-5700 4975)(-5700 5100);
WIRE 16 -1 (-5475 2375)(-5275 2375);
WIRE 16 -1 (-5475 2375)(-5475 1550);
WIRE 16 -1 (-5275 2500)(-5275 2375);
WIRE 16 -1 (-5275 2225)(-5275 2375);
WIRE 16 -1 (-5475 1550)(-5325 1550);
WIRE 16 -1 (-6400 5400)(-6150 5400);
WIRE 16 -1 (-6400 5475)(-6400 5400);
WIRE 16 -1 (-4500 5300)(-4500 5400);
WIRE 16 -1 (-4275 5400)(-4500 5400);
WIRE 16 -1 (-4500 5400)(-4750 5400);
WIRE 16 -1 (-4750 5300)(-4750 5400);
WIRE 16 -1 (-4975 5400)(-4750 5400);
WIRE 16 -1 (-4975 5300)(-4975 5400);
WIRE 16 -1 (-5300 5400)(-4975 5400);
WIRE 16 -1 (-5300 5500)(-5300 5400);
WIRE 16 -1 (-5300 5300)(-5300 5400);
WIRE 16 -1 (-5700 5400)(-5300 5400);
WIRE 16 -1 (-5700 5400)(-5700 5300);
WIRE 16 -1 (-5950 5400)(-5700 5400);
WIRE 16 -1 (-3950 5275)(-3950 5400);
WIRE 16 -1 (-3625 5400)(-3950 5400);
WIRE 16 -1 (-3950 5400)(-4075 5400);
WIRE 16 -1 (-3625 5450)(-3625 5400);
WIRE 16 -1 (-3625 5275)(-3625 5400);
WIRE 16 -1 (-4975 4150)(-4850 4150);
WIRE 16 -1 (-4975 4200)(-4975 4150);
WIRE 16 -1 (-4850 4200)(-4975 4200);
WIRE 16 -1 (-4975 4250)(-4975 4200);
WIRE 16 -1 (-4850 4250)(-4975 4250);
WIRE 16 -1 (-4975 4300)(-4975 4250);
WIRE 16 -1 (-4850 4300)(-4975 4300);
WIRE 16 -1 (-4975 4300)(-5750 4300);
WIRE 16 -1 (-5750 4300)(-5750 4450);
WIRE 16 -1 (-3750 4350)(-3100 4350);
FORCEPROP 0 LAST CDS_PHYS_NET_NAME CLK_GEN2_SMB_SADR
J 0
(-3725 4392);
PAINT MONO (-3725 4392);
DISPLAY INVISIBLE (-3725 4392);
FORCEPROP 0 LAST SIG_NAME CLK_GEN2_SMB_SADR
J 0
(-3650 4360);
DISPLAY 0.680851 (-3650 4360);
PAINT WHITE (-3650 4360);
WIRE 16 -1 (-4850 3700)(-5725 3700);
FORCEPROP 2 LAST SIG_NAME SMB_HOST_CLK_GEN2_3V3AUX_SCL
J 0
(-5685 3710);
DISPLAY 0.553191 (-5685 3710);
PAINT WHITE (-5685 3710);
WIRE 16 -1 (-4850 3650)(-5725 3650);
FORCEPROP 2 LAST SIG_NAME SMB_HOST_CLK_GEN2_3V3AUX_SDA
J 0
(-5685 3660);
DISPLAY 0.553191 (-5685 3660);
PAINT WHITE (-5685 3660);
WIRE 16 -1 (-6100 3550)(-4850 3550);
FORCEPROP 2 LAST SIG_NAME CLK_GEN2_BMC_RC_OE_R3_N
J 0
(-5860 3560);
DISPLAY 0.680851 (-5860 3560);
PAINT WHITE (-5860 3560);
FORCEPROP 2 LASTPROP $XRERR UNIQUE?
J 0
(-6100 3560);
DISPLAY 0.638298 (-6100 3560);
PAINT MONO (-6100 3560);
DISPLAY INVISIBLE (-6100 3560);
WIRE 16 -1 (-2825 3950)(-3750 3950);
FORCEPROP 2 LAST SIG_NAME CLK_100M_BMC_RC_DP_R
J 0
(-3660 3960);
DISPLAY 0.680851 (-3660 3960);
PAINT WHITE (-3660 3960);
FORCEPROP 2 LASTPROP $XRERR UNIQUE?
J 0
(-3900 3960);
DISPLAY 0.638298 (-3900 3960);
PAINT MONO (-3900 3960);
DISPLAY INVISIBLE (-3900 3960);
WIRE 16 -1 (-2825 3900)(-3750 3900);
FORCEPROP 2 LAST SIG_NAME CLK_100M_BMC_RC_DN_R
J 0
(-3660 3910);
DISPLAY 0.680851 (-3660 3910);
PAINT WHITE (-3660 3910);
FORCEPROP 2 LASTPROP $XRERR UNIQUE?
J 0
(-3900 3910);
DISPLAY 0.638298 (-3900 3910);
PAINT MONO (-3900 3910);
DISPLAY INVISIBLE (-3900 3910);
WIRE 16 -1 (-2825 3800)(-3750 3800);
FORCEPROP 2 LAST SIG_NAME CLK_100M_GPU_FPGA_DP_R
J 0
(-3660 3810);
DISPLAY 0.680851 (-3660 3810);
PAINT WHITE (-3660 3810);
FORCEPROP 2 LASTPROP $XRERR UNIQUE?
J 0
(-3900 3810);
DISPLAY 0.638298 (-3900 3810);
PAINT MONO (-3900 3810);
DISPLAY INVISIBLE (-3900 3810);
WIRE 16 -1 (-2825 3750)(-3750 3750);
FORCEPROP 2 LAST SIG_NAME CLK_100M_GPU_FPGA_DN_R
J 0
(-3660 3760);
DISPLAY 0.680851 (-3660 3760);
PAINT WHITE (-3660 3760);
FORCEPROP 2 LASTPROP $XRERR UNIQUE?
J 0
(-3900 3760);
DISPLAY 0.638298 (-3900 3760);
PAINT MONO (-3900 3760);
DISPLAY INVISIBLE (-3900 3760);
WIRE 16 -1 (-6100 3500)(-4850 3500);
FORCEPROP 2 LAST SIG_NAME CLK_GEN2_GPU_OE_N
J 0
(-5860 3510);
DISPLAY 0.680851 (-5860 3510);
PAINT WHITE (-5860 3510);
FORCEPROP 2 LASTPROP $XRERR UNIQUE?
J 0
(-6100 3510);
DISPLAY 0.638298 (-6100 3510);
PAINT MONO (-6100 3510);
DISPLAY INVISIBLE (-6100 3510);
WIRE 16 -1 (-5925 3250)(-4850 3250);
FORCEPROP 0 LAST CDS_PHYS_NET_NAME P3V3_PWRGD_CLKGEN
J 0
(-5900 3292);
PAINT MONO (-5900 3292);
DISPLAY INVISIBLE (-5900 3292);
FORCEPROP 0 LAST SIG_NAME P3V3_PWRGD_CLKGEN
J 0
(-5860 3260);
DISPLAY 0.680851 (-5860 3260);
PAINT WHITE (-5860 3260);
WIRE 16 -1 (-5925 3150)(-4850 3150);
FORCEPROP 0 LAST CDS_PHYS_NET_NAME FG_SS_EN
J 0
(-5900 3192);
PAINT MONO (-5900 3192);
DISPLAY INVISIBLE (-5900 3192);
FORCEPROP 0 LAST SIG_NAME FG_SS_EN
J 0
(-5860 3160);
DISPLAY 0.680851 (-5860 3160);
PAINT WHITE (-5860 3160);
WIRE 16 -1 (-1700 3900)(-2625 3900);
FORCEPROP 2 LAST SIG_NAME CLK_100M_BMC_RC_DN
J 0
(-2360 3910);
DISPLAY 0.680851 (-2360 3910);
PAINT WHITE (-2360 3910);
WIRE 16 -1 (-1700 3950)(-2625 3950);
FORCEPROP 2 LAST SIG_NAME CLK_100M_BMC_RC_DP
J 0
(-2360 3960);
DISPLAY 0.680851 (-2360 3960);
PAINT WHITE (-2360 3960);
WIRE 16 -1 (-8050 3500)(-6300 3500);
FORCEPROP 2 LAST SIG_NAME CLK_GEN2_GPU_FPGA_OE_OR_N
J 0
(-7385 3510);
DISPLAY 0.680851 (-7385 3510);
PAINT WHITE (-7385 3510);
WIRE 16 -1 (-7075 4100)(-7250 4100);
WIRE 16 -1 (-7250 4100)(-7250 4575);
WIRE 16 -1 (-7250 4100)(-7250 4000);
WIRE 16 -1 (-7250 4575)(-6475 4575);
FORCEPROP 2 LAST SIG_NAME CLK_GEN2_XTAL_IN_R
J 0
(-7185 4585);
DISPLAY 0.553191 (-7185 4585);
PAINT WHITE (-7185 4585);
FORCEPROP 2 LASTPROP $XRERR UNIQUE?
J 0
(-7425 4585);
DISPLAY 0.638298 (-7425 4585);
PAINT MONO (-7425 4585);
DISPLAY INVISIBLE (-7425 4585);
WIRE 16 -1 (-7975 3825)(-7975 3550);
WIRE 16 -1 (-7975 3550)(-6300 3550);
FORCEPROP 2 LAST SIG_NAME CLK_GEN2_BMC_RC_OE_N
J 0
(-7385 3560);
DISPLAY 0.680851 (-7385 3560);
PAINT WHITE (-7385 3560);
WIRE 16 -1 (-8050 3550)(-7975 3550);
WIRE 16 -1 (-2650 1425)(-2000 1425);
FORCEPROP 0 LAST CDS_PHYS_NET_NAME FG_SS_EN
J 0
(-2625 1467);
PAINT MONO (-2625 1467);
DISPLAY INVISIBLE (-2625 1467);
FORCEPROP 0 LAST SIG_NAME FG_SS_EN
J 0
(-2550 1435);
DISPLAY 0.680851 (-2550 1435);
PAINT WHITE (-2550 1435);
WIRE 16 -1 (-2650 1575)(-2650 1425);
WIRE 16 -1 (-2650 1425)(-2650 1300);
WIRE 16 -1 (-1325 1450)(-675 1450);
FORCEPROP 0 LAST CDS_PHYS_NET_NAME CLK_GEN2_SMB_SADR
J 0
(-1300 1492);
PAINT MONO (-1300 1492);
DISPLAY INVISIBLE (-1300 1492);
FORCEPROP 0 LAST SIG_NAME CLK_GEN2_SMB_SADR
J 0
(-1225 1460);
DISPLAY 0.680851 (-1225 1460);
PAINT WHITE (-1225 1460);
WIRE 16 -1 (-1325 1600)(-1325 1450);
WIRE 16 -1 (-1325 1450)(-1325 1325);
WIRE 16 -1 (-6525 1500)(-5425 1500);
FORCEPROP 2 LAST SIG_NAME GPU_FPGA_READY_R_N
J 0
(-6285 1510);
DISPLAY 0.680851 (-6285 1510);
PAINT WHITE (-6285 1510);
FORCEPROP 2 LASTPROP $XRERR UNIQUE?
J 0
(-6525 1510);
DISPLAY 0.638298 (-6525 1510);
PAINT MONO (-6525 1510);
DISPLAY INVISIBLE (-6525 1510);
WIRE 16 -1 (-1325 2400)(-1325 2250);
WIRE 16 -1 (-1325 2250)(-675 2250);
FORCEPROP 0 LAST CDS_PHYS_NET_NAME P3V3_PWRGD_CLKGEN
J 0
(-1300 2292);
PAINT MONO (-1300 2292);
DISPLAY INVISIBLE (-1300 2292);
FORCEPROP 0 LAST SIG_NAME P3V3_PWRGD_CLKGEN
J 0
(-1225 2260);
DISPLAY 0.680851 (-1225 2260);
PAINT WHITE (-1225 2260);
WIRE 16 -1 (-1700 3800)(-2625 3800);
FORCEPROP 2 LAST SIG_NAME CLK_100M_GPU_FPGA_DP
J 0
(-2360 3810);
DISPLAY 0.680851 (-2360 3810);
PAINT WHITE (-2360 3810);
WIRE 16 -1 (-1700 3750)(-2625 3750);
FORCEPROP 2 LAST SIG_NAME CLK_100M_GPU_FPGA_DN
J 0
(-2360 3760);
DISPLAY 0.680851 (-2360 3760);
PAINT WHITE (-2360 3760);
WIRE 16 -1 (-4825 1450)(-3825 1450);
FORCEPROP 2 LAST SIG_NAME CLK_GEN2_GPU_FPGA_OE_OR_N
J 0
(-4735 1460);
DISPLAY 0.680851 (-4735 1460);
PAINT WHITE (-4735 1460);
WIRE 16 -1 (-6325 1700)(-6325 1400);
WIRE 16 -1 (-6300 1400)(-6325 1400);
WIRE 16 -1 (-6325 1400)(-6525 1400);
WIRE 16 -1 (-5425 1400)(-6300 1400);
FORCEPROP 2 LAST SIG_NAME CLK_GEN2_GPU_FPGA_OE_R2_N
J 0
(-6285 1410);
DISPLAY 0.680851 (-6285 1410);
PAINT WHITE (-6285 1410);
FORCEPROP 2 LASTPROP $XRERR UNIQUE?
J 0
(-6525 1410);
DISPLAY 0.638298 (-6525 1410);
PAINT MONO (-6525 1410);
DISPLAY INVISIBLE (-6525 1410);
WIRE 16 -1 (-6300 1275)(-6300 1400);
DOT 1 (-6375 4100);
DOT 1 (-6325 1400);
DOT 1 (-7975 3550);
DOT 1 (-3600 3300);
DOT 1 (-6300 1400);
DOT 1 (-5275 2375);
DOT 1 (-7250 4100);
DOT 1 (-5300 4975);
DOT 1 (-5700 5400);
DOT 1 (-5300 5400);
DOT 1 (-4975 4250);
DOT 1 (-4975 4300);
DOT 1 (-4500 4975);
DOT 1 (-4750 5400);
DOT 1 (-4500 5400);
DOT 1 (-2650 1425);
DOT 1 (-1325 1450);
DOT 1 (-3625 4975);
DOT 1 (-3950 5400);
DOT 1 (-4975 5400);
DOT 1 (-4750 4975);
DOT 1 (-3625 5400);
DOT 1 (-4975 4200);
DOT 1 (-3600 3250);
DOT 1 (-3600 3200);
DOT 1 (-3600 3050);
DOT 1 (-3600 3400);
DOT 1 (-3600 3350);
DOT 1 (-4975 4975);
FORCENOTE
13 MA
(-5300 4375) 0;
DISPLAY LEFT (-5300 4375);
DISPLAY 0.851064 (-5300 4375);
PAINT WHITE (-5300 4375);
FORCENOTE
TO BMC
(-1325 3900) 0;
DISPLAY LEFT (-1325 3900);
DISPLAY 1.340425 (-1325 3900);
PAINT WHITE (-1325 3900);
FORCENOTE
TO GPU FPGA
(-1325 3750) 0;
DISPLAY LEFT (-1325 3750);
DISPLAY 1.340425 (-1325 3750);
PAINT WHITE (-1325 3750);
FORCENOTE
20 MA
(-5650 4325) 0;
DISPLAY LEFT (-5650 4325);
DISPLAY 0.851064 (-5650 4325);
PAINT WHITE (-5650 4325);
FORCENOTE
ADDRESS: 0XD4(8-BIT) / 0X6A(7-BIT)
(-4875 2575) 0;
DISPLAY LEFT (-4875 2575);
DISPLAY 1.595745 (-4875 2575);
PAINT SKYBLUE (-4875 2575);
QUIT
